FILE_TYPE = MACRO_DRAWING;
SET COLOR_WIRE YELLOW;
SET COLOR_PROP ORANGE;
SET COLOR_DOT WHITE;
SET COLOR_ARC YELLOW;
SET COLOR_BODY GREEN;
SET COLOR_NOTE PURPLE;
SET PROP_DISPLAY VALUE;
SET PAGE_NUMBER P318;
FORCEADD OFFPAGE..1
(-3250 -1250);
FORCEPROP 2 LAST $XR0 353 
J 0
(-3532 -1250);
DISPLAY 0.638298 (-3532 -1250);
PAINT MONO (-3532 -1250);
FORCEPROP 2 LAST CDS_LIB standard
J 0
(-3250 -1250);
DISPLAY INVISIBLE (-3250 -1250);
FORCEPROP 1 LAST OFFPAGE TRUE
J 0
(-2925 -1375);
DISPLAY 0.872340 (-2925 -1375);
PAINT AQUA (-2925 -1375);
DISPLAY INVISIBLE (-2925 -1375);
FORCEPROP 1 LAST COMMENT_BODY TRUE
J 0
(-3125 -1350);
DISPLAY 0.872340 (-3125 -1350);
PAINT GREEN (-3125 -1350);
DISPLAY INVISIBLE (-3125 -1350);
FORCEPROP 2 LAST PATH I1
J 0
(-3500 -1200);
DISPLAY 0.680851 (-3500 -1200);
DISPLAY INVISIBLE (-3500 -1200);
FORCEADD OFFPAGE..5
(-3250 -550);
FORCEPROP 2 LAST $XR0 127 
J 0
(-3505 -550);
DISPLAY 0.638298 (-3505 -550);
PAINT MONO (-3505 -550);
FORCEPROP 2 LAST CDS_LIB standard
J 0
(-3250 -550);
DISPLAY INVISIBLE (-3250 -550);
FORCEPROP 1 LAST OFFPAGE TRUE
J 0
(-2925 -675);
DISPLAY 0.872340 (-2925 -675);
PAINT AQUA (-2925 -675);
DISPLAY INVISIBLE (-2925 -675);
FORCEPROP 1 LAST COMMENT_BODY TRUE
J 0
(-3150 -625);
DISPLAY 1.170213 (-3150 -625);
PAINT GREEN (-3150 -625);
DISPLAY INVISIBLE (-3150 -625);
FORCEPROP 2 LAST PATH I10
J 0
(-3525 -500);
DISPLAY 0.680851 (-3525 -500);
DISPLAY INVISIBLE (-3525 -500);
FORCEADD OFFPAGE..1
(-3250 -450);
FORCEPROP 2 LAST $XR0 353 
J 0
(-3532 -450);
DISPLAY 0.638298 (-3532 -450);
PAINT MONO (-3532 -450);
FORCEPROP 2 LAST CDS_LIB standard
J 0
(-3250 -450);
DISPLAY INVISIBLE (-3250 -450);
FORCEPROP 1 LAST OFFPAGE TRUE
J 0
(-2925 -575);
DISPLAY 0.872340 (-2925 -575);
PAINT AQUA (-2925 -575);
DISPLAY INVISIBLE (-2925 -575);
FORCEPROP 1 LAST COMMENT_BODY TRUE
J 0
(-3125 -550);
DISPLAY 0.872340 (-3125 -550);
PAINT GREEN (-3125 -550);
DISPLAY INVISIBLE (-3125 -550);
FORCEPROP 2 LAST PATH I11
J 0
(-3500 -400);
DISPLAY 0.680851 (-3500 -400);
DISPLAY INVISIBLE (-3500 -400);
FORCEADD OFFPAGE..1
(-3250 -400);
FORCEPROP 2 LAST $XR0 353 
J 0
(-3532 -400);
DISPLAY 0.638298 (-3532 -400);
PAINT MONO (-3532 -400);
FORCEPROP 2 LAST CDS_LIB standard
J 0
(-3250 -400);
DISPLAY INVISIBLE (-3250 -400);
FORCEPROP 1 LAST OFFPAGE TRUE
J 0
(-2925 -525);
DISPLAY 0.872340 (-2925 -525);
PAINT AQUA (-2925 -525);
DISPLAY INVISIBLE (-2925 -525);
FORCEPROP 1 LAST COMMENT_BODY TRUE
J 0
(-3125 -500);
DISPLAY 0.872340 (-3125 -500);
PAINT GREEN (-3125 -500);
DISPLAY INVISIBLE (-3125 -500);
FORCEPROP 2 LAST PATH I12
J 0
(-3500 -350);
DISPLAY 0.680851 (-3500 -350);
DISPLAY INVISIBLE (-3500 -350);
FORCEADD OFFPAGE..1
(-3250 -300);
FORCEPROP 2 LAST $XR0 342 
J 0
(-3532 -300);
DISPLAY 0.638298 (-3532 -300);
PAINT MONO (-3532 -300);
FORCEPROP 2 LAST CDS_LIB standard
J 0
(-3250 -300);
DISPLAY INVISIBLE (-3250 -300);
FORCEPROP 1 LAST OFFPAGE TRUE
J 0
(-2925 -425);
DISPLAY 0.872340 (-2925 -425);
PAINT AQUA (-2925 -425);
DISPLAY INVISIBLE (-2925 -425);
FORCEPROP 1 LAST COMMENT_BODY TRUE
J 0
(-3125 -400);
DISPLAY 0.872340 (-3125 -400);
PAINT GREEN (-3125 -400);
DISPLAY INVISIBLE (-3125 -400);
FORCEPROP 2 LAST PATH I13
J 0
(-3500 -250);
DISPLAY 0.680851 (-3500 -250);
DISPLAY INVISIBLE (-3500 -250);
FORCEADD OFFPAGE..1
(-3250 -250);
FORCEPROP 2 LAST $XR0 342 
J 0
(-3532 -250);
DISPLAY 0.638298 (-3532 -250);
PAINT MONO (-3532 -250);
FORCEPROP 2 LAST CDS_LIB standard
J 0
(-3250 -250);
DISPLAY INVISIBLE (-3250 -250);
FORCEPROP 1 LAST OFFPAGE TRUE
J 0
(-2925 -375);
DISPLAY 0.872340 (-2925 -375);
PAINT AQUA (-2925 -375);
DISPLAY INVISIBLE (-2925 -375);
FORCEPROP 1 LAST COMMENT_BODY TRUE
J 0
(-3125 -350);
DISPLAY 0.872340 (-3125 -350);
PAINT GREEN (-3125 -350);
DISPLAY INVISIBLE (-3125 -350);
FORCEPROP 2 LAST PATH I14
J 0
(-3500 -200);
DISPLAY 0.680851 (-3500 -200);
DISPLAY INVISIBLE (-3500 -200);
FORCEADD UNIVERSAL_GND..1
(-2150 -1700);
FORCEPROP 3 LASTPIN (-2150 -1650) SIG_NAME GND\g
J 0
(-2140 -1640);
DISPLAY 0.659574 (-2140 -1640);
PAINT MONO (-2140 -1640);
DISPLAY INVISIBLE (-2140 -1640);
FORCEPROP 2 LAST CDS_LIB pure_quanta_power
J 0
(-2150 -1700);
DISPLAY INVISIBLE (-2150 -1700);
FORCEPROP 1 LAST HDL_POWER GND
J 1
(-2125 -1775);
DISPLAY 0.872340 (-2125 -1775);
PAINT GREEN (-2125 -1775);
DISPLAY INVISIBLE (-2125 -1775);
FORCEPROP 1 LAST PATH I15
J 0
(-2075 -1700);
DISPLAY 0.872340 (-2075 -1700);
PAINT AQUA (-2075 -1700);
DISPLAY INVISIBLE (-2075 -1700);
FORCEADD CONN112_10137002101LF..1
(-1050 200);
FORCEPROP 1 LAST LOCATION J110
J 0
(-1800 2000);
DISPLAY 0.723404 (-1800 2000);
PAINT GREEN (-1800 2000);
FORCEPROP 0 LAST $SEC 1
J 0
(-1800 2125);
DISPLAY 0.680851 (-1800 2125);
PAINT MONO (-1800 2125);
DISPLAY INVISIBLE (-1800 2125);
FORCEPROP 0 LAST CDS_SEC 1
J 0
(-1800 2125);
DISPLAY 1.021277 (-1800 2125);
DISPLAY INVISIBLE (-1800 2125);
FORCEPROP 0 LASTPIN (-1975 -700) $PN A5
J 2
(-1985 -690);
DISPLAY 0.680851 (-1985 -690);
PAINT MONO (-1985 -690);
FORCEPROP 0 LASTPIN (-1975 100) $PN A6
J 2
(-1985 110);
DISPLAY 0.680851 (-1985 110);
PAINT MONO (-1985 110);
FORCEPROP 0 LASTPIN (-1975 900) $PN A7
J 2
(-1985 910);
DISPLAY 0.680851 (-1985 910);
PAINT MONO (-1985 910);
FORCEPROP 0 LASTPIN (-1975 1700) $PN A8
J 2
(-1985 1710);
DISPLAY 0.680851 (-1985 1710);
PAINT MONO (-1985 1710);
FORCEPROP 0 LASTPIN (-1975 -750) $PN B5
J 2
(-1985 -740);
DISPLAY 0.680851 (-1985 -740);
PAINT MONO (-1985 -740);
FORCEPROP 0 LASTPIN (-1975 50) $PN B6
J 2
(-1985 60);
DISPLAY 0.680851 (-1985 60);
PAINT MONO (-1985 60);
FORCEPROP 0 LASTPIN (-1975 850) $PN B7
J 2
(-1985 860);
DISPLAY 0.680851 (-1985 860);
PAINT MONO (-1985 860);
FORCEPROP 0 LASTPIN (-1975 1650) $PN B8
J 2
(-1985 1660);
DISPLAY 0.680851 (-1985 1660);
PAINT MONO (-1985 1660);
FORCEPROP 0 LASTPIN (-1975 -800) $PN C5
J 2
(-1985 -790);
DISPLAY 0.680851 (-1985 -790);
PAINT MONO (-1985 -790);
FORCEPROP 0 LASTPIN (-1975 0) $PN C6
J 2
(-1985 10);
DISPLAY 0.680851 (-1985 10);
PAINT MONO (-1985 10);
FORCEPROP 0 LASTPIN (-1975 800) $PN C7
J 2
(-1985 810);
DISPLAY 0.680851 (-1985 810);
PAINT MONO (-1985 810);
FORCEPROP 0 LASTPIN (-1975 1600) $PN C8
J 2
(-1985 1610);
DISPLAY 0.680851 (-1985 1610);
PAINT MONO (-1985 1610);
FORCEPROP 0 LASTPIN (-1975 -850) $PN D5
J 2
(-1985 -840);
DISPLAY 0.680851 (-1985 -840);
PAINT MONO (-1985 -840);
FORCEPROP 0 LASTPIN (-1975 -50) $PN D6
J 2
(-1985 -40);
DISPLAY 0.680851 (-1985 -40);
PAINT MONO (-1985 -40);
FORCEPROP 0 LASTPIN (-1975 750) $PN D7
J 2
(-1985 760);
DISPLAY 0.680851 (-1985 760);
PAINT MONO (-1985 760);
FORCEPROP 0 LASTPIN (-1975 1550) $PN D8
J 2
(-1985 1560);
DISPLAY 0.680851 (-1985 1560);
PAINT MONO (-1985 1560);
FORCEPROP 0 LASTPIN (-1975 -900) $PN E5
J 2
(-1985 -890);
DISPLAY 0.680851 (-1985 -890);
PAINT MONO (-1985 -890);
FORCEPROP 0 LASTPIN (-1975 -100) $PN E6
J 2
(-1985 -90);
DISPLAY 0.680851 (-1985 -90);
PAINT MONO (-1985 -90);
FORCEPROP 0 LASTPIN (-1975 700) $PN E7
J 2
(-1985 710);
DISPLAY 0.680851 (-1985 710);
PAINT MONO (-1985 710);
FORCEPROP 0 LASTPIN (-1975 1500) $PN E8
J 2
(-1985 1510);
DISPLAY 0.680851 (-1985 1510);
PAINT MONO (-1985 1510);
FORCEPROP 0 LASTPIN (-1975 -950) $PN F5
J 2
(-1985 -940);
DISPLAY 0.680851 (-1985 -940);
PAINT MONO (-1985 -940);
FORCEPROP 0 LASTPIN (-1975 -150) $PN F6
J 2
(-1985 -140);
DISPLAY 0.680851 (-1985 -140);
PAINT MONO (-1985 -140);
FORCEPROP 0 LASTPIN (-1975 650) $PN F7
J 2
(-1985 660);
DISPLAY 0.680851 (-1985 660);
PAINT MONO (-1985 660);
FORCEPROP 0 LASTPIN (-1975 1450) $PN F8
J 2
(-1985 1460);
DISPLAY 0.680851 (-1985 1460);
PAINT MONO (-1985 1460);
FORCEPROP 0 LASTPIN (-1975 -1000) $PN G5
J 2
(-1985 -990);
DISPLAY 0.680851 (-1985 -990);
PAINT MONO (-1985 -990);
FORCEPROP 0 LASTPIN (-1975 -200) $PN G6
J 2
(-1985 -190);
DISPLAY 0.680851 (-1985 -190);
PAINT MONO (-1985 -190);
FORCEPROP 0 LASTPIN (-1975 600) $PN G7
J 2
(-1985 610);
DISPLAY 0.680851 (-1985 610);
PAINT MONO (-1985 610);
FORCEPROP 0 LASTPIN (-1975 1400) $PN G8
J 2
(-1985 1410);
DISPLAY 0.680851 (-1985 1410);
PAINT MONO (-1985 1410);
FORCEPROP 0 LASTPIN (-1975 -1050) $PN H5
J 2
(-1985 -1040);
DISPLAY 0.680851 (-1985 -1040);
PAINT MONO (-1985 -1040);
FORCEPROP 0 LASTPIN (-1975 -250) $PN H6
J 2
(-1985 -240);
DISPLAY 0.680851 (-1985 -240);
PAINT MONO (-1985 -240);
FORCEPROP 0 LASTPIN (-1975 550) $PN H7
J 2
(-1985 560);
DISPLAY 0.680851 (-1985 560);
PAINT MONO (-1985 560);
FORCEPROP 0 LASTPIN (-1975 1350) $PN H8
J 2
(-1985 1360);
DISPLAY 0.680851 (-1985 1360);
PAINT MONO (-1985 1360);
FORCEPROP 0 LASTPIN (-1975 -1100) $PN I5
J 2
(-1985 -1090);
DISPLAY 0.680851 (-1985 -1090);
PAINT MONO (-1985 -1090);
FORCEPROP 0 LASTPIN (-1975 -300) $PN I6
J 2
(-1985 -290);
DISPLAY 0.680851 (-1985 -290);
PAINT MONO (-1985 -290);
FORCEPROP 0 LASTPIN (-1975 500) $PN I7
J 2
(-1985 510);
DISPLAY 0.680851 (-1985 510);
PAINT MONO (-1985 510);
FORCEPROP 0 LASTPIN (-1975 1300) $PN I8
J 2
(-1985 1310);
DISPLAY 0.680851 (-1985 1310);
PAINT MONO (-1985 1310);
FORCEPROP 0 LASTPIN (-1975 -1150) $PN J5
J 2
(-1985 -1140);
DISPLAY 0.680851 (-1985 -1140);
PAINT MONO (-1985 -1140);
FORCEPROP 0 LASTPIN (-1975 -350) $PN J6
J 2
(-1985 -340);
DISPLAY 0.680851 (-1985 -340);
PAINT MONO (-1985 -340);
FORCEPROP 0 LASTPIN (-1975 450) $PN J7
J 2
(-1985 460);
DISPLAY 0.680851 (-1985 460);
PAINT MONO (-1985 460);
FORCEPROP 0 LASTPIN (-1975 1250) $PN J8
J 2
(-1985 1260);
DISPLAY 0.680851 (-1985 1260);
PAINT MONO (-1985 1260);
FORCEPROP 0 LASTPIN (-1975 -1200) $PN K5
J 2
(-1985 -1190);
DISPLAY 0.680851 (-1985 -1190);
PAINT MONO (-1985 -1190);
FORCEPROP 0 LASTPIN (-1975 -400) $PN K6
J 2
(-1985 -390);
DISPLAY 0.680851 (-1985 -390);
PAINT MONO (-1985 -390);
FORCEPROP 0 LASTPIN (-1975 400) $PN K7
J 2
(-1985 410);
DISPLAY 0.680851 (-1985 410);
PAINT MONO (-1985 410);
FORCEPROP 0 LASTPIN (-1975 1200) $PN K8
J 2
(-1985 1210);
DISPLAY 0.680851 (-1985 1210);
PAINT MONO (-1985 1210);
FORCEPROP 0 LASTPIN (-1975 -1250) $PN L5
J 2
(-1985 -1240);
DISPLAY 0.680851 (-1985 -1240);
PAINT MONO (-1985 -1240);
FORCEPROP 0 LASTPIN (-1975 -450) $PN L6
J 2
(-1985 -440);
DISPLAY 0.680851 (-1985 -440);
PAINT MONO (-1985 -440);
FORCEPROP 0 LASTPIN (-1975 350) $PN L7
J 2
(-1985 360);
DISPLAY 0.680851 (-1985 360);
PAINT MONO (-1985 360);
FORCEPROP 0 LASTPIN (-1975 1150) $PN L8
J 2
(-1985 1160);
DISPLAY 0.680851 (-1985 1160);
PAINT MONO (-1985 1160);
FORCEPROP 0 LASTPIN (-1975 -1300) $PN M5
J 2
(-1985 -1290);
DISPLAY 0.680851 (-1985 -1290);
PAINT MONO (-1985 -1290);
FORCEPROP 0 LASTPIN (-1975 -500) $PN M6
J 2
(-1985 -490);
DISPLAY 0.680851 (-1985 -490);
PAINT MONO (-1985 -490);
FORCEPROP 0 LASTPIN (-1975 300) $PN M7
J 2
(-1985 310);
DISPLAY 0.680851 (-1985 310);
PAINT MONO (-1985 310);
FORCEPROP 0 LASTPIN (-1975 1100) $PN M8
J 2
(-1985 1110);
DISPLAY 0.680851 (-1985 1110);
PAINT MONO (-1985 1110);
FORCEPROP 0 LASTPIN (-1975 -1350) $PN N5
J 2
(-1985 -1340);
DISPLAY 0.680851 (-1985 -1340);
PAINT MONO (-1985 -1340);
FORCEPROP 0 LASTPIN (-1975 -550) $PN N6
J 2
(-1985 -540);
DISPLAY 0.680851 (-1985 -540);
PAINT MONO (-1985 -540);
FORCEPROP 0 LASTPIN (-1975 250) $PN N7
J 2
(-1985 260);
DISPLAY 0.680851 (-1985 260);
PAINT MONO (-1985 260);
FORCEPROP 0 LASTPIN (-1975 1050) $PN N8
J 2
(-1985 1060);
DISPLAY 0.680851 (-1985 1060);
PAINT MONO (-1985 1060);
FORCEPROP 1 LAST MATERIAL IO
J 0
(-1795 1882);
DISPLAY 0.723404 (-1795 1882);
PAINT GREEN (-1795 1882);
FORCEPROP 2 LAST PART_TYPE THLF
J 0
(-1800 2075);
DISPLAY 1.021277 (-1800 2075);
FORCEPROP 2 LAST CDS_LIB pure_quanta
J 0
(-1050 200);
DISPLAY INVISIBLE (-1050 200);
FORCEPROP 1 LAST NEEDS_NO_SIZE TRUE
J 0
(-1050 200);
DISPLAY 0.723404 (-1050 200);
PAINT GREEN (-1050 200);
DISPLAY INVISIBLE (-1050 200);
FORCEPROP 1 LAST CDS_LMAN_SYM_OUTLINE -775,1650,775,-1650
J 0
(-1050 200);
DISPLAY 0.468085 (-1050 200);
PAINT GREEN (-1050 200);
DISPLAY INVISIBLE (-1050 200);
FORCEPROP 0 LAST VALUE CONN112_10137002-101LF
J 0
(-1775 2200);
DISPLAY 1.021277 (-1775 2200);
DISPLAY INVISIBLE (-1775 2200);
FORCEPROP 1 LAST PATH I16
J 0
(-1050 200);
DISPLAY 0.723404 (-1050 200);
PAINT GREEN (-1050 200);
DISPLAY INVISIBLE (-1050 200);
FORCEPROP 1 LAST PART_NUMBER DFHSB2FR012
J 0
(-1800 1950);
DISPLAY 0.723404 (-1800 1950);
PAINT GREEN (-1800 1950);
DISPLAY INVISIBLE (-1800 1950);
FORCEADD OFFPAGE..2
R 2
(-3250 50);
FORCEPROP 2 LAST $XR0 341 
J 0
(-3505 50);
DISPLAY 0.638298 (-3505 50);
PAINT MONO (-3505 50);
FORCEPROP 2 LAST CDS_LIB standard
J 0
(-3250 50);
DISPLAY INVISIBLE (-3250 50);
FORCEPROP 1 LAST OFFPAGE TRUE
J 2
(-3575 -75);
DISPLAY 0.872340 (-3575 -75);
PAINT AQUA (-3575 -75);
DISPLAY INVISIBLE (-3575 -75);
FORCEPROP 1 LAST COMMENT_BODY TRUE
J 2
(-3205 -45);
DISPLAY 0.872340 (-3205 -45);
PAINT GREEN (-3205 -45);
DISPLAY INVISIBLE (-3205 -45);
FORCEPROP 2 LAST PATH I17
J 0
(-3525 100);
DISPLAY 0.680851 (-3525 100);
DISPLAY INVISIBLE (-3525 100);
FORCEADD OFFPAGE..5
(-3250 0);
FORCEPROP 2 LAST $XR0 341 
J 0
(-3505 0);
DISPLAY 0.638298 (-3505 0);
PAINT MONO (-3505 0);
FORCEPROP 2 LAST CDS_LIB standard
J 0
(-3250 0);
DISPLAY INVISIBLE (-3250 0);
FORCEPROP 1 LAST OFFPAGE TRUE
J 0
(-2925 -125);
DISPLAY 0.872340 (-2925 -125);
PAINT AQUA (-2925 -125);
DISPLAY INVISIBLE (-2925 -125);
FORCEPROP 1 LAST COMMENT_BODY TRUE
J 0
(-3150 -75);
DISPLAY 1.170213 (-3150 -75);
PAINT GREEN (-3150 -75);
DISPLAY INVISIBLE (-3150 -75);
FORCEPROP 2 LAST PATH I18
J 0
(-3525 50);
DISPLAY 0.680851 (-3525 50);
DISPLAY INVISIBLE (-3525 50);
FORCEADD OFFPAGE..5
(-3250 -150);
FORCEPROP 2 LAST $XR0 352 
J 0
(-3505 -150);
DISPLAY 0.638298 (-3505 -150);
PAINT MONO (-3505 -150);
FORCEPROP 2 LAST CDS_LIB standard
J 0
(-3250 -150);
DISPLAY INVISIBLE (-3250 -150);
FORCEPROP 1 LAST OFFPAGE TRUE
J 0
(-2925 -275);
DISPLAY 0.872340 (-2925 -275);
PAINT AQUA (-2925 -275);
DISPLAY INVISIBLE (-2925 -275);
FORCEPROP 1 LAST COMMENT_BODY TRUE
J 0
(-3150 -225);
DISPLAY 1.170213 (-3150 -225);
PAINT GREEN (-3150 -225);
DISPLAY INVISIBLE (-3150 -225);
FORCEPROP 2 LAST PATH I19
J 0
(-3525 -100);
DISPLAY 0.680851 (-3525 -100);
DISPLAY INVISIBLE (-3525 -100);
FORCEADD OFFPAGE..1
(-3250 -1300);
FORCEPROP 2 LAST $XR0 353 
J 0
(-3532 -1300);
DISPLAY 0.638298 (-3532 -1300);
PAINT MONO (-3532 -1300);
FORCEPROP 2 LAST CDS_LIB standard
J 0
(-3250 -1300);
DISPLAY INVISIBLE (-3250 -1300);
FORCEPROP 1 LAST OFFPAGE TRUE
J 0
(-2925 -1425);
DISPLAY 0.872340 (-2925 -1425);
PAINT AQUA (-2925 -1425);
DISPLAY INVISIBLE (-2925 -1425);
FORCEPROP 1 LAST COMMENT_BODY TRUE
J 0
(-3125 -1400);
DISPLAY 0.872340 (-3125 -1400);
PAINT GREEN (-3125 -1400);
DISPLAY INVISIBLE (-3125 -1400);
FORCEPROP 2 LAST PATH I2
J 0
(-3500 -1250);
DISPLAY 0.680851 (-3500 -1250);
DISPLAY INVISIBLE (-3500 -1250);
FORCEADD OFFPAGE..2
R 2
(-3250 -100);
FORCEPROP 2 LAST $XR0 352 
J 0
(-3505 -100);
DISPLAY 0.638298 (-3505 -100);
PAINT MONO (-3505 -100);
FORCEPROP 2 LAST CDS_LIB standard
J 0
(-3250 -100);
DISPLAY INVISIBLE (-3250 -100);
FORCEPROP 1 LAST OFFPAGE TRUE
J 2
(-3575 -225);
DISPLAY 0.872340 (-3575 -225);
PAINT AQUA (-3575 -225);
DISPLAY INVISIBLE (-3575 -225);
FORCEPROP 1 LAST COMMENT_BODY TRUE
J 2
(-3205 -195);
DISPLAY 0.872340 (-3205 -195);
PAINT GREEN (-3205 -195);
DISPLAY INVISIBLE (-3205 -195);
FORCEPROP 2 LAST PATH I20
J 0
(-3525 -50);
DISPLAY 0.680851 (-3525 -50);
DISPLAY INVISIBLE (-3525 -50);
FORCEADD OFFPAGE..1
(-3250 300);
FORCEPROP 2 LAST $XR0 353 
J 0
(-3532 300);
DISPLAY 0.638298 (-3532 300);
PAINT MONO (-3532 300);
FORCEPROP 2 LAST CDS_LIB standard
J 0
(-3250 300);
DISPLAY INVISIBLE (-3250 300);
FORCEPROP 1 LAST OFFPAGE TRUE
J 0
(-2925 175);
DISPLAY 0.872340 (-2925 175);
PAINT AQUA (-2925 175);
DISPLAY INVISIBLE (-2925 175);
FORCEPROP 1 LAST COMMENT_BODY TRUE
J 0
(-3125 200);
DISPLAY 0.872340 (-3125 200);
PAINT GREEN (-3125 200);
DISPLAY INVISIBLE (-3125 200);
FORCEPROP 2 LAST PATH I21
J 0
(-3500 350);
DISPLAY 0.680851 (-3500 350);
DISPLAY INVISIBLE (-3500 350);
FORCEADD OFFPAGE..1
(-3250 350);
FORCEPROP 2 LAST $XR0 353 
J 0
(-3532 350);
DISPLAY 0.638298 (-3532 350);
PAINT MONO (-3532 350);
FORCEPROP 2 LAST CDS_LIB standard
J 0
(-3250 350);
DISPLAY INVISIBLE (-3250 350);
FORCEPROP 1 LAST OFFPAGE TRUE
J 0
(-2925 225);
DISPLAY 0.872340 (-2925 225);
PAINT AQUA (-2925 225);
DISPLAY INVISIBLE (-2925 225);
FORCEPROP 1 LAST COMMENT_BODY TRUE
J 0
(-3125 250);
DISPLAY 0.872340 (-3125 250);
PAINT GREEN (-3125 250);
DISPLAY INVISIBLE (-3125 250);
FORCEPROP 2 LAST PATH I22
J 0
(-3500 400);
DISPLAY 0.680851 (-3500 400);
DISPLAY INVISIBLE (-3500 400);
FORCEADD OFFPAGE..1
(-3250 450);
FORCEPROP 2 LAST $XR0 342 
J 0
(-3532 450);
DISPLAY 0.638298 (-3532 450);
PAINT MONO (-3532 450);
FORCEPROP 2 LAST CDS_LIB standard
J 0
(-3250 450);
DISPLAY INVISIBLE (-3250 450);
FORCEPROP 1 LAST OFFPAGE TRUE
J 0
(-2925 325);
DISPLAY 0.872340 (-2925 325);
PAINT AQUA (-2925 325);
DISPLAY INVISIBLE (-2925 325);
FORCEPROP 1 LAST COMMENT_BODY TRUE
J 0
(-3125 350);
DISPLAY 0.872340 (-3125 350);
PAINT GREEN (-3125 350);
DISPLAY INVISIBLE (-3125 350);
FORCEPROP 2 LAST PATH I23
J 0
(-3500 500);
DISPLAY 0.680851 (-3500 500);
DISPLAY INVISIBLE (-3500 500);
FORCEADD OFFPAGE..1
(-3250 500);
FORCEPROP 2 LAST $XR0 342 
J 0
(-3532 500);
DISPLAY 0.638298 (-3532 500);
PAINT MONO (-3532 500);
FORCEPROP 2 LAST CDS_LIB standard
J 0
(-3250 500);
DISPLAY INVISIBLE (-3250 500);
FORCEPROP 1 LAST OFFPAGE TRUE
J 0
(-2925 375);
DISPLAY 0.872340 (-2925 375);
PAINT AQUA (-2925 375);
DISPLAY INVISIBLE (-2925 375);
FORCEPROP 1 LAST COMMENT_BODY TRUE
J 0
(-3125 400);
DISPLAY 0.872340 (-3125 400);
PAINT GREEN (-3125 400);
DISPLAY INVISIBLE (-3125 400);
FORCEPROP 2 LAST PATH I24
J 0
(-3500 550);
DISPLAY 0.680851 (-3500 550);
DISPLAY INVISIBLE (-3500 550);
FORCEADD OFFPAGE..5
(-3250 750);
FORCEPROP 2 LAST $XR0 341 
J 0
(-3505 750);
DISPLAY 0.638298 (-3505 750);
PAINT MONO (-3505 750);
FORCEPROP 2 LAST CDS_LIB standard
J 0
(-3250 750);
DISPLAY INVISIBLE (-3250 750);
FORCEPROP 1 LAST OFFPAGE TRUE
J 0
(-2925 625);
DISPLAY 0.872340 (-2925 625);
PAINT AQUA (-2925 625);
DISPLAY INVISIBLE (-2925 625);
FORCEPROP 1 LAST COMMENT_BODY TRUE
J 0
(-3150 675);
DISPLAY 1.170213 (-3150 675);
PAINT GREEN (-3150 675);
DISPLAY INVISIBLE (-3150 675);
FORCEPROP 2 LAST PATH I25
J 0
(-3525 800);
DISPLAY 0.680851 (-3525 800);
DISPLAY INVISIBLE (-3525 800);
FORCEADD OFFPAGE..2
R 2
(-3250 800);
FORCEPROP 2 LAST $XR0 341 
J 0
(-3505 800);
DISPLAY 0.638298 (-3505 800);
PAINT MONO (-3505 800);
FORCEPROP 2 LAST CDS_LIB standard
J 0
(-3250 800);
DISPLAY INVISIBLE (-3250 800);
FORCEPROP 1 LAST OFFPAGE TRUE
J 2
(-3575 675);
DISPLAY 0.872340 (-3575 675);
PAINT AQUA (-3575 675);
DISPLAY INVISIBLE (-3575 675);
FORCEPROP 1 LAST COMMENT_BODY TRUE
J 2
(-3205 705);
DISPLAY 0.872340 (-3205 705);
PAINT GREEN (-3205 705);
DISPLAY INVISIBLE (-3205 705);
FORCEPROP 2 LAST PATH I26
J 0
(-3525 850);
DISPLAY 0.680851 (-3525 850);
DISPLAY INVISIBLE (-3525 850);
FORCEADD OFFPAGE..2
R 2
(-3250 650);
FORCEPROP 2 LAST $XR0 352 
J 0
(-3505 650);
DISPLAY 0.638298 (-3505 650);
PAINT MONO (-3505 650);
FORCEPROP 2 LAST CDS_LIB standard
J 0
(-3250 650);
DISPLAY INVISIBLE (-3250 650);
FORCEPROP 1 LAST OFFPAGE TRUE
J 2
(-3575 525);
DISPLAY 0.872340 (-3575 525);
PAINT AQUA (-3575 525);
DISPLAY INVISIBLE (-3575 525);
FORCEPROP 1 LAST COMMENT_BODY TRUE
J 2
(-3205 555);
DISPLAY 0.872340 (-3205 555);
PAINT GREEN (-3205 555);
DISPLAY INVISIBLE (-3205 555);
FORCEPROP 2 LAST PATH I27
J 0
(-3525 700);
DISPLAY 0.680851 (-3525 700);
DISPLAY INVISIBLE (-3525 700);
FORCEADD OFFPAGE..5
(-3250 600);
FORCEPROP 2 LAST $XR0 352 
J 0
(-3505 600);
DISPLAY 0.638298 (-3505 600);
PAINT MONO (-3505 600);
FORCEPROP 2 LAST CDS_LIB standard
J 0
(-3250 600);
DISPLAY INVISIBLE (-3250 600);
FORCEPROP 1 LAST OFFPAGE TRUE
J 0
(-2925 475);
DISPLAY 0.872340 (-2925 475);
PAINT AQUA (-2925 475);
DISPLAY INVISIBLE (-2925 475);
FORCEPROP 1 LAST COMMENT_BODY TRUE
J 0
(-3150 525);
DISPLAY 1.170213 (-3150 525);
PAINT GREEN (-3150 525);
DISPLAY INVISIBLE (-3150 525);
FORCEPROP 2 LAST PATH I28
J 0
(-3525 650);
DISPLAY 0.680851 (-3525 650);
DISPLAY INVISIBLE (-3525 650);
FORCEADD OFFPAGE..1
(-3250 1050);
FORCEPROP 2 LAST $XR0 129 
J 0
(-3532 1050);
DISPLAY 0.638298 (-3532 1050);
PAINT MONO (-3532 1050);
FORCEPROP 2 LAST CDS_LIB standard
J 0
(-3250 1050);
DISPLAY INVISIBLE (-3250 1050);
FORCEPROP 1 LAST OFFPAGE TRUE
J 0
(-2925 925);
DISPLAY 0.872340 (-2925 925);
PAINT AQUA (-2925 925);
DISPLAY INVISIBLE (-2925 925);
FORCEPROP 1 LAST COMMENT_BODY TRUE
J 0
(-3125 950);
DISPLAY 0.872340 (-3125 950);
PAINT GREEN (-3125 950);
DISPLAY INVISIBLE (-3125 950);
FORCEPROP 2 LAST PATH I29
J 0
(-3500 1100);
DISPLAY 0.680851 (-3500 1100);
DISPLAY INVISIBLE (-3500 1100);
FORCEADD OFFPAGE..5
(-3250 -1000);
FORCEPROP 2 LAST $XR0 352 
J 0
(-3505 -1000);
DISPLAY 0.638298 (-3505 -1000);
PAINT MONO (-3505 -1000);
FORCEPROP 2 LAST CDS_LIB standard
J 0
(-3250 -1000);
DISPLAY INVISIBLE (-3250 -1000);
FORCEPROP 1 LAST OFFPAGE TRUE
J 0
(-2925 -1125);
DISPLAY 0.872340 (-2925 -1125);
PAINT AQUA (-2925 -1125);
DISPLAY INVISIBLE (-2925 -1125);
FORCEPROP 1 LAST COMMENT_BODY TRUE
J 0
(-3150 -1075);
DISPLAY 1.170213 (-3150 -1075);
PAINT GREEN (-3150 -1075);
DISPLAY INVISIBLE (-3150 -1075);
FORCEPROP 2 LAST PATH I3
J 0
(-3525 -950);
DISPLAY 0.680851 (-3525 -950);
DISPLAY INVISIBLE (-3525 -950);
FORCEADD OFFPAGE..1
(-3250 900);
FORCEPROP 2 LAST $XR0 128 
J 0
(-3532 900);
DISPLAY 0.638298 (-3532 900);
PAINT MONO (-3532 900);
FORCEPROP 2 LAST CDS_LIB standard
J 0
(-3250 900);
DISPLAY INVISIBLE (-3250 900);
FORCEPROP 1 LAST OFFPAGE TRUE
J 0
(-2925 775);
DISPLAY 0.872340 (-2925 775);
PAINT AQUA (-2925 775);
DISPLAY INVISIBLE (-2925 775);
FORCEPROP 1 LAST COMMENT_BODY TRUE
J 0
(-3125 800);
DISPLAY 0.872340 (-3125 800);
PAINT GREEN (-3125 800);
DISPLAY INVISIBLE (-3125 800);
FORCEPROP 2 LAST PATH I30
J 0
(-3500 950);
DISPLAY 0.680851 (-3500 950);
DISPLAY INVISIBLE (-3500 950);
FORCEADD OFFPAGE..1
(-3250 1150);
FORCEPROP 2 LAST $XR0 353 
J 0
(-3532 1150);
DISPLAY 0.638298 (-3532 1150);
PAINT MONO (-3532 1150);
FORCEPROP 2 LAST CDS_LIB standard
J 0
(-3250 1150);
DISPLAY INVISIBLE (-3250 1150);
FORCEPROP 1 LAST OFFPAGE TRUE
J 0
(-2925 1025);
DISPLAY 0.872340 (-2925 1025);
PAINT AQUA (-2925 1025);
DISPLAY INVISIBLE (-2925 1025);
FORCEPROP 1 LAST COMMENT_BODY TRUE
J 0
(-3125 1050);
DISPLAY 0.872340 (-3125 1050);
PAINT GREEN (-3125 1050);
DISPLAY INVISIBLE (-3125 1050);
FORCEPROP 2 LAST PATH I31
J 0
(-3500 1200);
DISPLAY 0.680851 (-3500 1200);
DISPLAY INVISIBLE (-3500 1200);
FORCEADD OFFPAGE..1
(-3250 1200);
FORCEPROP 2 LAST $XR0 353 
J 0
(-3532 1200);
DISPLAY 0.638298 (-3532 1200);
PAINT MONO (-3532 1200);
FORCEPROP 2 LAST CDS_LIB standard
J 0
(-3250 1200);
DISPLAY INVISIBLE (-3250 1200);
FORCEPROP 1 LAST OFFPAGE TRUE
J 0
(-2925 1075);
DISPLAY 0.872340 (-2925 1075);
PAINT AQUA (-2925 1075);
DISPLAY INVISIBLE (-2925 1075);
FORCEPROP 1 LAST COMMENT_BODY TRUE
J 0
(-3125 1100);
DISPLAY 0.872340 (-3125 1100);
PAINT GREEN (-3125 1100);
DISPLAY INVISIBLE (-3125 1100);
FORCEPROP 2 LAST PATH I32
J 0
(-3500 1250);
DISPLAY 0.680851 (-3500 1250);
DISPLAY INVISIBLE (-3500 1250);
FORCEADD OFFPAGE..1
(-3250 1300);
FORCEPROP 2 LAST $XR0 342 
J 0
(-3532 1300);
DISPLAY 0.638298 (-3532 1300);
PAINT MONO (-3532 1300);
FORCEPROP 2 LAST CDS_LIB standard
J 0
(-3250 1300);
DISPLAY INVISIBLE (-3250 1300);
FORCEPROP 1 LAST OFFPAGE TRUE
J 0
(-2925 1175);
DISPLAY 0.872340 (-2925 1175);
PAINT AQUA (-2925 1175);
DISPLAY INVISIBLE (-2925 1175);
FORCEPROP 1 LAST COMMENT_BODY TRUE
J 0
(-3125 1200);
DISPLAY 0.872340 (-3125 1200);
PAINT GREEN (-3125 1200);
DISPLAY INVISIBLE (-3125 1200);
FORCEPROP 2 LAST PATH I33
J 0
(-3500 1350);
DISPLAY 0.680851 (-3500 1350);
DISPLAY INVISIBLE (-3500 1350);
FORCEADD OFFPAGE..1
(-3250 1350);
FORCEPROP 2 LAST $XR0 342 
J 0
(-3532 1350);
DISPLAY 0.638298 (-3532 1350);
PAINT MONO (-3532 1350);
FORCEPROP 2 LAST CDS_LIB standard
J 0
(-3250 1350);
DISPLAY INVISIBLE (-3250 1350);
FORCEPROP 1 LAST OFFPAGE TRUE
J 0
(-2925 1225);
DISPLAY 0.872340 (-2925 1225);
PAINT AQUA (-2925 1225);
DISPLAY INVISIBLE (-2925 1225);
FORCEPROP 1 LAST COMMENT_BODY TRUE
J 0
(-3125 1250);
DISPLAY 0.872340 (-3125 1250);
PAINT GREEN (-3125 1250);
DISPLAY INVISIBLE (-3125 1250);
FORCEPROP 2 LAST PATH I34
J 0
(-3500 1400);
DISPLAY 0.680851 (-3500 1400);
DISPLAY INVISIBLE (-3500 1400);
FORCEADD OFFPAGE..5
(-3250 1450);
FORCEPROP 2 LAST $XR0 352 
J 0
(-3505 1450);
DISPLAY 0.638298 (-3505 1450);
PAINT MONO (-3505 1450);
FORCEPROP 2 LAST CDS_LIB standard
J 0
(-3250 1450);
DISPLAY INVISIBLE (-3250 1450);
FORCEPROP 1 LAST OFFPAGE TRUE
J 0
(-2925 1325);
DISPLAY 0.872340 (-2925 1325);
PAINT AQUA (-2925 1325);
DISPLAY INVISIBLE (-2925 1325);
FORCEPROP 1 LAST COMMENT_BODY TRUE
J 0
(-3150 1375);
DISPLAY 1.170213 (-3150 1375);
PAINT GREEN (-3150 1375);
DISPLAY INVISIBLE (-3150 1375);
FORCEPROP 2 LAST PATH I35
J 0
(-3525 1500);
DISPLAY 0.680851 (-3525 1500);
DISPLAY INVISIBLE (-3525 1500);
FORCEADD OFFPAGE..2
R 2
(-3250 1500);
FORCEPROP 2 LAST $XR0 352 
J 0
(-3505 1500);
DISPLAY 0.638298 (-3505 1500);
PAINT MONO (-3505 1500);
FORCEPROP 2 LAST CDS_LIB standard
J 0
(-3250 1500);
DISPLAY INVISIBLE (-3250 1500);
FORCEPROP 1 LAST OFFPAGE TRUE
J 2
(-3575 1375);
DISPLAY 0.872340 (-3575 1375);
PAINT AQUA (-3575 1375);
DISPLAY INVISIBLE (-3575 1375);
FORCEPROP 1 LAST COMMENT_BODY TRUE
J 2
(-3205 1405);
DISPLAY 0.872340 (-3205 1405);
PAINT GREEN (-3205 1405);
DISPLAY INVISIBLE (-3205 1405);
FORCEPROP 2 LAST PATH I36
J 0
(-3525 1550);
DISPLAY 0.680851 (-3525 1550);
DISPLAY INVISIBLE (-3525 1550);
FORCEADD OFFPAGE..5
(-3250 1600);
FORCEPROP 2 LAST $XR0 341 
J 0
(-3505 1600);
DISPLAY 0.638298 (-3505 1600);
PAINT MONO (-3505 1600);
FORCEPROP 2 LAST CDS_LIB standard
J 0
(-3250 1600);
DISPLAY INVISIBLE (-3250 1600);
FORCEPROP 1 LAST OFFPAGE TRUE
J 0
(-2925 1475);
DISPLAY 0.872340 (-2925 1475);
PAINT AQUA (-2925 1475);
DISPLAY INVISIBLE (-2925 1475);
FORCEPROP 1 LAST COMMENT_BODY TRUE
J 0
(-3150 1525);
DISPLAY 1.170213 (-3150 1525);
PAINT GREEN (-3150 1525);
DISPLAY INVISIBLE (-3150 1525);
FORCEPROP 2 LAST PATH I37
J 0
(-3525 1650);
DISPLAY 0.680851 (-3525 1650);
DISPLAY INVISIBLE (-3525 1650);
FORCEADD OFFPAGE..2
R 2
(-3250 1650);
FORCEPROP 2 LAST $XR0 341 
J 0
(-3505 1650);
DISPLAY 0.638298 (-3505 1650);
PAINT MONO (-3505 1650);
FORCEPROP 2 LAST CDS_LIB standard
J 0
(-3250 1650);
DISPLAY INVISIBLE (-3250 1650);
FORCEPROP 1 LAST OFFPAGE TRUE
J 2
(-3575 1525);
DISPLAY 0.872340 (-3575 1525);
PAINT AQUA (-3575 1525);
DISPLAY INVISIBLE (-3575 1525);
FORCEPROP 1 LAST COMMENT_BODY TRUE
J 2
(-3205 1555);
DISPLAY 0.872340 (-3205 1555);
PAINT GREEN (-3205 1555);
DISPLAY INVISIBLE (-3205 1555);
FORCEPROP 2 LAST PATH I38
J 0
(-3525 1700);
DISPLAY 0.680851 (-3525 1700);
DISPLAY INVISIBLE (-3525 1700);
FORCEADD OFFPAGE..1
(1500 -1250);
FORCEPROP 2 LAST $XR0 353 
J 0
(1248 -1250);
DISPLAY 0.638298 (1248 -1250);
PAINT MONO (1248 -1250);
FORCEPROP 2 LAST CDS_LIB standard
J 0
(1500 -1250);
DISPLAY INVISIBLE (1500 -1250);
FORCEPROP 1 LAST OFFPAGE TRUE
J 0
(1825 -1375);
DISPLAY 0.872340 (1825 -1375);
PAINT AQUA (1825 -1375);
DISPLAY INVISIBLE (1825 -1375);
FORCEPROP 1 LAST COMMENT_BODY TRUE
J 0
(1625 -1350);
DISPLAY 0.872340 (1625 -1350);
PAINT GREEN (1625 -1350);
DISPLAY INVISIBLE (1625 -1350);
FORCEPROP 2 LAST PATH I39
J 0
(1250 -1200);
DISPLAY 0.680851 (1250 -1200);
DISPLAY INVISIBLE (1250 -1200);
FORCEADD OFFPAGE..1
(-3250 -1150);
FORCEPROP 2 LAST $XR0 342 
J 0
(-3532 -1150);
DISPLAY 0.638298 (-3532 -1150);
PAINT MONO (-3532 -1150);
FORCEPROP 2 LAST CDS_LIB standard
J 0
(-3250 -1150);
DISPLAY INVISIBLE (-3250 -1150);
FORCEPROP 1 LAST OFFPAGE TRUE
J 0
(-2925 -1275);
DISPLAY 0.872340 (-2925 -1275);
PAINT AQUA (-2925 -1275);
DISPLAY INVISIBLE (-2925 -1275);
FORCEPROP 1 LAST COMMENT_BODY TRUE
J 0
(-3125 -1250);
DISPLAY 0.872340 (-3125 -1250);
PAINT GREEN (-3125 -1250);
DISPLAY INVISIBLE (-3125 -1250);
FORCEPROP 2 LAST PATH I4
J 0
(-3500 -1100);
DISPLAY 0.680851 (-3500 -1100);
DISPLAY INVISIBLE (-3500 -1100);
FORCEADD OFFPAGE..1
(1500 -1200);
FORCEPROP 2 LAST $XR0 353 
J 0
(1248 -1200);
DISPLAY 0.638298 (1248 -1200);
PAINT MONO (1248 -1200);
FORCEPROP 2 LAST CDS_LIB standard
J 0
(1500 -1200);
DISPLAY INVISIBLE (1500 -1200);
FORCEPROP 1 LAST OFFPAGE TRUE
J 0
(1825 -1325);
DISPLAY 0.872340 (1825 -1325);
PAINT AQUA (1825 -1325);
DISPLAY INVISIBLE (1825 -1325);
FORCEPROP 1 LAST COMMENT_BODY TRUE
J 0
(1625 -1300);
DISPLAY 0.872340 (1625 -1300);
PAINT GREEN (1625 -1300);
DISPLAY INVISIBLE (1625 -1300);
FORCEPROP 2 LAST PATH I40
J 0
(1250 -1150);
DISPLAY 0.680851 (1250 -1150);
DISPLAY INVISIBLE (1250 -1150);
FORCEADD OFFPAGE..1
(1500 -1050);
FORCEPROP 2 LAST $XR0 342 
J 0
(1248 -1050);
DISPLAY 0.638298 (1248 -1050);
PAINT MONO (1248 -1050);
FORCEPROP 2 LAST CDS_LIB standard
J 0
(1500 -1050);
DISPLAY INVISIBLE (1500 -1050);
FORCEPROP 1 LAST OFFPAGE TRUE
J 0
(1825 -1175);
DISPLAY 0.872340 (1825 -1175);
PAINT AQUA (1825 -1175);
DISPLAY INVISIBLE (1825 -1175);
FORCEPROP 1 LAST COMMENT_BODY TRUE
J 0
(1625 -1150);
DISPLAY 0.872340 (1625 -1150);
PAINT GREEN (1625 -1150);
DISPLAY INVISIBLE (1625 -1150);
FORCEPROP 2 LAST PATH I41
J 0
(1250 -1000);
DISPLAY 0.680851 (1250 -1000);
DISPLAY INVISIBLE (1250 -1000);
FORCEADD OFFPAGE..1
(1500 -1100);
FORCEPROP 2 LAST $XR0 342 
J 0
(1248 -1100);
DISPLAY 0.638298 (1248 -1100);
PAINT MONO (1248 -1100);
FORCEPROP 2 LAST CDS_LIB standard
J 0
(1500 -1100);
DISPLAY INVISIBLE (1500 -1100);
FORCEPROP 1 LAST OFFPAGE TRUE
J 0
(1825 -1225);
DISPLAY 0.872340 (1825 -1225);
PAINT AQUA (1825 -1225);
DISPLAY INVISIBLE (1825 -1225);
FORCEPROP 1 LAST COMMENT_BODY TRUE
J 0
(1625 -1200);
DISPLAY 0.872340 (1625 -1200);
PAINT GREEN (1625 -1200);
DISPLAY INVISIBLE (1625 -1200);
FORCEPROP 2 LAST PATH I42
J 0
(1250 -1050);
DISPLAY 0.680851 (1250 -1050);
DISPLAY INVISIBLE (1250 -1050);
FORCEADD OFFPAGE..5
(1500 -950);
FORCEPROP 2 LAST $XR0 352 
J 0
(1245 -950);
DISPLAY 0.638298 (1245 -950);
PAINT MONO (1245 -950);
FORCEPROP 2 LAST CDS_LIB standard
J 0
(1500 -950);
DISPLAY INVISIBLE (1500 -950);
FORCEPROP 1 LAST OFFPAGE TRUE
J 0
(1825 -1075);
DISPLAY 0.872340 (1825 -1075);
PAINT AQUA (1825 -1075);
DISPLAY INVISIBLE (1825 -1075);
FORCEPROP 1 LAST COMMENT_BODY TRUE
J 0
(1600 -1025);
DISPLAY 1.170213 (1600 -1025);
PAINT GREEN (1600 -1025);
DISPLAY INVISIBLE (1600 -1025);
FORCEPROP 2 LAST PATH I43
J 0
(1225 -900);
DISPLAY 0.680851 (1225 -900);
DISPLAY INVISIBLE (1225 -900);
FORCEADD OFFPAGE..2
R 2
(1500 -900);
FORCEPROP 2 LAST $XR0 352 
J 0
(1245 -900);
DISPLAY 0.638298 (1245 -900);
PAINT MONO (1245 -900);
FORCEPROP 2 LAST CDS_LIB standard
J 0
(1500 -900);
DISPLAY INVISIBLE (1500 -900);
FORCEPROP 1 LAST OFFPAGE TRUE
J 2
(1175 -1025);
DISPLAY 0.872340 (1175 -1025);
PAINT AQUA (1175 -1025);
DISPLAY INVISIBLE (1175 -1025);
FORCEPROP 1 LAST COMMENT_BODY TRUE
J 2
(1545 -995);
DISPLAY 0.872340 (1545 -995);
PAINT GREEN (1545 -995);
DISPLAY INVISIBLE (1545 -995);
FORCEPROP 2 LAST PATH I44
J 0
(1225 -850);
DISPLAY 0.680851 (1225 -850);
DISPLAY INVISIBLE (1225 -850);
FORCEADD OFFPAGE..5
(1500 -800);
FORCEPROP 2 LAST $XR0 341 
J 0
(1245 -800);
DISPLAY 0.638298 (1245 -800);
PAINT MONO (1245 -800);
FORCEPROP 2 LAST CDS_LIB standard
J 0
(1500 -800);
DISPLAY INVISIBLE (1500 -800);
FORCEPROP 1 LAST OFFPAGE TRUE
J 0
(1825 -925);
DISPLAY 0.872340 (1825 -925);
PAINT AQUA (1825 -925);
DISPLAY INVISIBLE (1825 -925);
FORCEPROP 1 LAST COMMENT_BODY TRUE
J 0
(1600 -875);
DISPLAY 1.170213 (1600 -875);
PAINT GREEN (1600 -875);
DISPLAY INVISIBLE (1600 -875);
FORCEPROP 2 LAST PATH I45
J 0
(1225 -750);
DISPLAY 0.680851 (1225 -750);
DISPLAY INVISIBLE (1225 -750);
FORCEADD OFFPAGE..2
R 2
(1500 -750);
FORCEPROP 2 LAST $XR0 341 
J 0
(1245 -750);
DISPLAY 0.638298 (1245 -750);
PAINT MONO (1245 -750);
FORCEPROP 2 LAST CDS_LIB standard
J 0
(1500 -750);
DISPLAY INVISIBLE (1500 -750);
FORCEPROP 1 LAST OFFPAGE TRUE
J 2
(1175 -875);
DISPLAY 0.872340 (1175 -875);
PAINT AQUA (1175 -875);
DISPLAY INVISIBLE (1175 -875);
FORCEPROP 1 LAST COMMENT_BODY TRUE
J 2
(1545 -845);
DISPLAY 0.872340 (1545 -845);
PAINT GREEN (1545 -845);
DISPLAY INVISIBLE (1545 -845);
FORCEPROP 2 LAST PATH I46
J 0
(1225 -700);
DISPLAY 0.680851 (1225 -700);
DISPLAY INVISIBLE (1225 -700);
FORCEADD OFFPAGE..1
(1500 -650);
FORCEPROP 2 LAST $XR0 129 
J 0
(1248 -650);
DISPLAY 0.638298 (1248 -650);
PAINT MONO (1248 -650);
FORCEPROP 2 LAST CDS_LIB standard
J 0
(1500 -650);
DISPLAY INVISIBLE (1500 -650);
FORCEPROP 1 LAST OFFPAGE TRUE
J 0
(1825 -775);
DISPLAY 0.872340 (1825 -775);
PAINT AQUA (1825 -775);
DISPLAY INVISIBLE (1825 -775);
FORCEPROP 1 LAST COMMENT_BODY TRUE
J 0
(1625 -750);
DISPLAY 0.872340 (1625 -750);
PAINT GREEN (1625 -750);
DISPLAY INVISIBLE (1625 -750);
FORCEPROP 2 LAST PATH I47
J 0
(1250 -600);
DISPLAY 0.680851 (1250 -600);
DISPLAY INVISIBLE (1250 -600);
FORCEADD OFFPAGE..1
(1500 -500);
FORCEPROP 2 LAST $XR0 128 
J 0
(1248 -500);
DISPLAY 0.638298 (1248 -500);
PAINT MONO (1248 -500);
FORCEPROP 2 LAST CDS_LIB standard
J 0
(1500 -500);
DISPLAY INVISIBLE (1500 -500);
FORCEPROP 1 LAST OFFPAGE TRUE
J 0
(1825 -625);
DISPLAY 0.872340 (1825 -625);
PAINT AQUA (1825 -625);
DISPLAY INVISIBLE (1825 -625);
FORCEPROP 1 LAST COMMENT_BODY TRUE
J 0
(1625 -600);
DISPLAY 0.872340 (1625 -600);
PAINT GREEN (1625 -600);
DISPLAY INVISIBLE (1625 -600);
FORCEPROP 2 LAST PATH I48
J 0
(1250 -450);
DISPLAY 0.680851 (1250 -450);
DISPLAY INVISIBLE (1250 -450);
FORCEADD OFFPAGE..1
(1500 -350);
FORCEPROP 2 LAST $XR0 353 
J 0
(1248 -350);
DISPLAY 0.638298 (1248 -350);
PAINT MONO (1248 -350);
FORCEPROP 2 LAST CDS_LIB standard
J 0
(1500 -350);
DISPLAY INVISIBLE (1500 -350);
FORCEPROP 1 LAST OFFPAGE TRUE
J 0
(1825 -475);
DISPLAY 0.872340 (1825 -475);
PAINT AQUA (1825 -475);
DISPLAY INVISIBLE (1825 -475);
FORCEPROP 1 LAST COMMENT_BODY TRUE
J 0
(1625 -450);
DISPLAY 0.872340 (1625 -450);
PAINT GREEN (1625 -450);
DISPLAY INVISIBLE (1625 -450);
FORCEPROP 2 LAST PATH I49
J 0
(1250 -300);
DISPLAY 0.680851 (1250 -300);
DISPLAY INVISIBLE (1250 -300);
FORCEADD OFFPAGE..1
(-3250 -1100);
FORCEPROP 2 LAST $XR0 342 
J 0
(-3532 -1100);
DISPLAY 0.638298 (-3532 -1100);
PAINT MONO (-3532 -1100);
FORCEPROP 2 LAST CDS_LIB standard
J 0
(-3250 -1100);
DISPLAY INVISIBLE (-3250 -1100);
FORCEPROP 1 LAST OFFPAGE TRUE
J 0
(-2925 -1225);
DISPLAY 0.872340 (-2925 -1225);
PAINT AQUA (-2925 -1225);
DISPLAY INVISIBLE (-2925 -1225);
FORCEPROP 1 LAST COMMENT_BODY TRUE
J 0
(-3125 -1200);
DISPLAY 0.872340 (-3125 -1200);
PAINT GREEN (-3125 -1200);
DISPLAY INVISIBLE (-3125 -1200);
FORCEPROP 2 LAST PATH I5
J 0
(-3500 -1050);
DISPLAY 0.680851 (-3500 -1050);
DISPLAY INVISIBLE (-3500 -1050);
FORCEADD OFFPAGE..1
(1500 -250);
FORCEPROP 2 LAST $XR0 342 
J 0
(1248 -250);
DISPLAY 0.638298 (1248 -250);
PAINT MONO (1248 -250);
FORCEPROP 2 LAST CDS_LIB standard
J 0
(1500 -250);
DISPLAY INVISIBLE (1500 -250);
FORCEPROP 1 LAST OFFPAGE TRUE
J 0
(1825 -375);
DISPLAY 0.872340 (1825 -375);
PAINT AQUA (1825 -375);
DISPLAY INVISIBLE (1825 -375);
FORCEPROP 1 LAST COMMENT_BODY TRUE
J 0
(1625 -350);
DISPLAY 0.872340 (1625 -350);
PAINT GREEN (1625 -350);
DISPLAY INVISIBLE (1625 -350);
FORCEPROP 2 LAST PATH I50
J 0
(1250 -200);
DISPLAY 0.680851 (1250 -200);
DISPLAY INVISIBLE (1250 -200);
FORCEADD OFFPAGE..1
(1500 -400);
FORCEPROP 2 LAST $XR0 353 
J 0
(1248 -400);
DISPLAY 0.638298 (1248 -400);
PAINT MONO (1248 -400);
FORCEPROP 2 LAST CDS_LIB standard
J 0
(1500 -400);
DISPLAY INVISIBLE (1500 -400);
FORCEPROP 1 LAST OFFPAGE TRUE
J 0
(1825 -525);
DISPLAY 0.872340 (1825 -525);
PAINT AQUA (1825 -525);
DISPLAY INVISIBLE (1825 -525);
FORCEPROP 1 LAST COMMENT_BODY TRUE
J 0
(1625 -500);
DISPLAY 0.872340 (1625 -500);
PAINT GREEN (1625 -500);
DISPLAY INVISIBLE (1625 -500);
FORCEPROP 2 LAST PATH I51
J 0
(1250 -350);
DISPLAY 0.680851 (1250 -350);
DISPLAY INVISIBLE (1250 -350);
FORCEADD OFFPAGE..1
(1500 -200);
FORCEPROP 2 LAST $XR0 342 
J 0
(1248 -200);
DISPLAY 0.638298 (1248 -200);
PAINT MONO (1248 -200);
FORCEPROP 2 LAST CDS_LIB standard
J 0
(1500 -200);
DISPLAY INVISIBLE (1500 -200);
FORCEPROP 1 LAST OFFPAGE TRUE
J 0
(1825 -325);
DISPLAY 0.872340 (1825 -325);
PAINT AQUA (1825 -325);
DISPLAY INVISIBLE (1825 -325);
FORCEPROP 1 LAST COMMENT_BODY TRUE
J 0
(1625 -300);
DISPLAY 0.872340 (1625 -300);
PAINT GREEN (1625 -300);
DISPLAY INVISIBLE (1625 -300);
FORCEPROP 2 LAST PATH I52
J 0
(1250 -150);
DISPLAY 0.680851 (1250 -150);
DISPLAY INVISIBLE (1250 -150);
FORCEADD UNIVERSAL_GND..1
(2575 -1700);
FORCEPROP 3 LASTPIN (2575 -1650) SIG_NAME GND\g
J 0
(2585 -1640);
DISPLAY 0.659574 (2585 -1640);
PAINT MONO (2585 -1640);
DISPLAY INVISIBLE (2585 -1640);
FORCEPROP 2 LAST CDS_LIB pure_quanta_power
J 0
(2575 -1700);
DISPLAY INVISIBLE (2575 -1700);
FORCEPROP 1 LAST HDL_POWER GND
J 1
(2600 -1775);
DISPLAY 0.872340 (2600 -1775);
PAINT GREEN (2600 -1775);
DISPLAY INVISIBLE (2600 -1775);
FORCEPROP 1 LAST PATH I53
J 0
(2650 -1700);
DISPLAY 0.872340 (2650 -1700);
PAINT AQUA (2650 -1700);
DISPLAY INVISIBLE (2650 -1700);
FORCEADD OFFPAGE..5
(1500 -100);
FORCEPROP 2 LAST $XR0 352 
J 0
(1245 -100);
DISPLAY 0.638298 (1245 -100);
PAINT MONO (1245 -100);
FORCEPROP 2 LAST CDS_LIB standard
J 0
(1500 -100);
DISPLAY INVISIBLE (1500 -100);
FORCEPROP 1 LAST OFFPAGE TRUE
J 0
(1825 -225);
DISPLAY 0.872340 (1825 -225);
PAINT AQUA (1825 -225);
DISPLAY INVISIBLE (1825 -225);
FORCEPROP 1 LAST COMMENT_BODY TRUE
J 0
(1600 -175);
DISPLAY 1.170213 (1600 -175);
PAINT GREEN (1600 -175);
DISPLAY INVISIBLE (1600 -175);
FORCEPROP 2 LAST PATH I54
J 0
(1225 -50);
DISPLAY 0.680851 (1225 -50);
DISPLAY INVISIBLE (1225 -50);
FORCEADD OFFPAGE..2
R 2
(1500 -50);
FORCEPROP 2 LAST $XR0 352 
J 0
(1245 -50);
DISPLAY 0.638298 (1245 -50);
PAINT MONO (1245 -50);
FORCEPROP 2 LAST CDS_LIB standard
J 0
(1500 -50);
DISPLAY INVISIBLE (1500 -50);
FORCEPROP 1 LAST OFFPAGE TRUE
J 2
(1175 -175);
DISPLAY 0.872340 (1175 -175);
PAINT AQUA (1175 -175);
DISPLAY INVISIBLE (1175 -175);
FORCEPROP 1 LAST COMMENT_BODY TRUE
J 2
(1545 -145);
DISPLAY 0.872340 (1545 -145);
PAINT GREEN (1545 -145);
DISPLAY INVISIBLE (1545 -145);
FORCEPROP 2 LAST PATH I55
J 0
(1225 0);
DISPLAY 0.680851 (1225 0);
DISPLAY INVISIBLE (1225 0);
FORCEADD OFFPAGE..5
(1500 50);
FORCEPROP 2 LAST $XR0 341 
J 0
(1245 50);
DISPLAY 0.638298 (1245 50);
PAINT MONO (1245 50);
FORCEPROP 2 LAST CDS_LIB standard
J 0
(1500 50);
DISPLAY INVISIBLE (1500 50);
FORCEPROP 1 LAST OFFPAGE TRUE
J 0
(1825 -75);
DISPLAY 0.872340 (1825 -75);
PAINT AQUA (1825 -75);
DISPLAY INVISIBLE (1825 -75);
FORCEPROP 1 LAST COMMENT_BODY TRUE
J 0
(1600 -25);
DISPLAY 1.170213 (1600 -25);
PAINT GREEN (1600 -25);
DISPLAY INVISIBLE (1600 -25);
FORCEPROP 2 LAST PATH I56
J 0
(1225 100);
DISPLAY 0.680851 (1225 100);
DISPLAY INVISIBLE (1225 100);
FORCEADD OFFPAGE..2
R 2
(1500 100);
FORCEPROP 2 LAST $XR0 341 
J 0
(1245 100);
DISPLAY 0.638298 (1245 100);
PAINT MONO (1245 100);
FORCEPROP 2 LAST CDS_LIB standard
J 0
(1500 100);
DISPLAY INVISIBLE (1500 100);
FORCEPROP 1 LAST OFFPAGE TRUE
J 2
(1175 -25);
DISPLAY 0.872340 (1175 -25);
PAINT AQUA (1175 -25);
DISPLAY INVISIBLE (1175 -25);
FORCEPROP 1 LAST COMMENT_BODY TRUE
J 2
(1545 5);
DISPLAY 0.872340 (1545 5);
PAINT GREEN (1545 5);
DISPLAY INVISIBLE (1545 5);
FORCEPROP 2 LAST PATH I57
J 0
(1225 150);
DISPLAY 0.680851 (1225 150);
DISPLAY INVISIBLE (1225 150);
FORCEADD OFFPAGE..1
(1500 500);
FORCEPROP 2 LAST $XR0 342 
J 0
(1248 500);
DISPLAY 0.638298 (1248 500);
PAINT MONO (1248 500);
FORCEPROP 2 LAST CDS_LIB standard
J 0
(1500 500);
DISPLAY INVISIBLE (1500 500);
FORCEPROP 1 LAST OFFPAGE TRUE
J 0
(1825 375);
DISPLAY 0.872340 (1825 375);
PAINT AQUA (1825 375);
DISPLAY INVISIBLE (1825 375);
FORCEPROP 1 LAST COMMENT_BODY TRUE
J 0
(1625 400);
DISPLAY 0.872340 (1625 400);
PAINT GREEN (1625 400);
DISPLAY INVISIBLE (1625 400);
FORCEPROP 2 LAST PATH I58
J 0
(1250 550);
DISPLAY 0.680851 (1250 550);
DISPLAY INVISIBLE (1250 550);
FORCEADD OFFPAGE..1
(1500 400);
FORCEPROP 2 LAST $XR0 353 
J 0
(1248 400);
DISPLAY 0.638298 (1248 400);
PAINT MONO (1248 400);
FORCEPROP 2 LAST CDS_LIB standard
J 0
(1500 400);
DISPLAY INVISIBLE (1500 400);
FORCEPROP 1 LAST OFFPAGE TRUE
J 0
(1825 275);
DISPLAY 0.872340 (1825 275);
PAINT AQUA (1825 275);
DISPLAY INVISIBLE (1825 275);
FORCEPROP 1 LAST COMMENT_BODY TRUE
J 0
(1625 300);
DISPLAY 0.872340 (1625 300);
PAINT GREEN (1625 300);
DISPLAY INVISIBLE (1625 300);
FORCEPROP 2 LAST PATH I59
J 0
(1250 450);
DISPLAY 0.680851 (1250 450);
DISPLAY INVISIBLE (1250 450);
FORCEADD OFFPAGE..2
R 2
(-3250 -950);
FORCEPROP 2 LAST $XR0 352 
J 0
(-3505 -950);
DISPLAY 0.638298 (-3505 -950);
PAINT MONO (-3505 -950);
FORCEPROP 2 LAST CDS_LIB standard
J 0
(-3250 -950);
DISPLAY INVISIBLE (-3250 -950);
FORCEPROP 1 LAST OFFPAGE TRUE
J 2
(-3575 -1075);
DISPLAY 0.872340 (-3575 -1075);
PAINT AQUA (-3575 -1075);
DISPLAY INVISIBLE (-3575 -1075);
FORCEPROP 1 LAST COMMENT_BODY TRUE
J 2
(-3205 -1045);
DISPLAY 0.872340 (-3205 -1045);
PAINT GREEN (-3205 -1045);
DISPLAY INVISIBLE (-3205 -1045);
FORCEPROP 2 LAST PATH I6
J 0
(-3525 -900);
DISPLAY 0.680851 (-3525 -900);
DISPLAY INVISIBLE (-3525 -900);
FORCEADD OFFPAGE..1
(1500 350);
FORCEPROP 2 LAST $XR0 353 
J 0
(1248 350);
DISPLAY 0.638298 (1248 350);
PAINT MONO (1248 350);
FORCEPROP 2 LAST CDS_LIB standard
J 0
(1500 350);
DISPLAY INVISIBLE (1500 350);
FORCEPROP 1 LAST OFFPAGE TRUE
J 0
(1825 225);
DISPLAY 0.872340 (1825 225);
PAINT AQUA (1825 225);
DISPLAY INVISIBLE (1825 225);
FORCEPROP 1 LAST COMMENT_BODY TRUE
J 0
(1625 250);
DISPLAY 0.872340 (1625 250);
PAINT GREEN (1625 250);
DISPLAY INVISIBLE (1625 250);
FORCEPROP 2 LAST PATH I60
J 0
(1250 400);
DISPLAY 0.680851 (1250 400);
DISPLAY INVISIBLE (1250 400);
FORCEADD OFFPAGE..1
(1500 550);
FORCEPROP 2 LAST $XR0 342 
J 0
(1248 550);
DISPLAY 0.638298 (1248 550);
PAINT MONO (1248 550);
FORCEPROP 2 LAST CDS_LIB standard
J 0
(1500 550);
DISPLAY INVISIBLE (1500 550);
FORCEPROP 1 LAST OFFPAGE TRUE
J 0
(1825 425);
DISPLAY 0.872340 (1825 425);
PAINT AQUA (1825 425);
DISPLAY INVISIBLE (1825 425);
FORCEPROP 1 LAST COMMENT_BODY TRUE
J 0
(1625 450);
DISPLAY 0.872340 (1625 450);
PAINT GREEN (1625 450);
DISPLAY INVISIBLE (1625 450);
FORCEPROP 2 LAST PATH I61
J 0
(1250 600);
DISPLAY 0.680851 (1250 600);
DISPLAY INVISIBLE (1250 600);
FORCEADD OFFPAGE..5
(1500 650);
FORCEPROP 2 LAST $XR0 352 
J 0
(1245 650);
DISPLAY 0.638298 (1245 650);
PAINT MONO (1245 650);
FORCEPROP 2 LAST CDS_LIB standard
J 0
(1500 650);
DISPLAY INVISIBLE (1500 650);
FORCEPROP 1 LAST OFFPAGE TRUE
J 0
(1825 525);
DISPLAY 0.872340 (1825 525);
PAINT AQUA (1825 525);
DISPLAY INVISIBLE (1825 525);
FORCEPROP 1 LAST COMMENT_BODY TRUE
J 0
(1600 575);
DISPLAY 1.170213 (1600 575);
PAINT GREEN (1600 575);
DISPLAY INVISIBLE (1600 575);
FORCEPROP 2 LAST PATH I62
J 0
(1225 700);
DISPLAY 0.680851 (1225 700);
DISPLAY INVISIBLE (1225 700);
FORCEADD OFFPAGE..2
R 2
(1500 700);
FORCEPROP 2 LAST $XR0 352 
J 0
(1245 700);
DISPLAY 0.638298 (1245 700);
PAINT MONO (1245 700);
FORCEPROP 2 LAST CDS_LIB standard
J 0
(1500 700);
DISPLAY INVISIBLE (1500 700);
FORCEPROP 1 LAST OFFPAGE TRUE
J 2
(1175 575);
DISPLAY 0.872340 (1175 575);
PAINT AQUA (1175 575);
DISPLAY INVISIBLE (1175 575);
FORCEPROP 1 LAST COMMENT_BODY TRUE
J 2
(1545 605);
DISPLAY 0.872340 (1545 605);
PAINT GREEN (1545 605);
DISPLAY INVISIBLE (1545 605);
FORCEPROP 2 LAST PATH I63
J 0
(1225 750);
DISPLAY 0.680851 (1225 750);
DISPLAY INVISIBLE (1225 750);
FORCEADD OFFPAGE..5
(1500 800);
FORCEPROP 2 LAST $XR0 341 
J 0
(1245 800);
DISPLAY 0.638298 (1245 800);
PAINT MONO (1245 800);
FORCEPROP 2 LAST CDS_LIB standard
J 0
(1500 800);
DISPLAY INVISIBLE (1500 800);
FORCEPROP 1 LAST OFFPAGE TRUE
J 0
(1825 675);
DISPLAY 0.872340 (1825 675);
PAINT AQUA (1825 675);
DISPLAY INVISIBLE (1825 675);
FORCEPROP 1 LAST COMMENT_BODY TRUE
J 0
(1600 725);
DISPLAY 1.170213 (1600 725);
PAINT GREEN (1600 725);
DISPLAY INVISIBLE (1600 725);
FORCEPROP 2 LAST PATH I64
J 0
(1225 850);
DISPLAY 0.680851 (1225 850);
DISPLAY INVISIBLE (1225 850);
FORCEADD OFFPAGE..2
R 2
(1500 850);
FORCEPROP 2 LAST $XR0 341 
J 0
(1245 850);
DISPLAY 0.638298 (1245 850);
PAINT MONO (1245 850);
FORCEPROP 2 LAST CDS_LIB standard
J 0
(1500 850);
DISPLAY INVISIBLE (1500 850);
FORCEPROP 1 LAST OFFPAGE TRUE
J 2
(1175 725);
DISPLAY 0.872340 (1175 725);
PAINT AQUA (1175 725);
DISPLAY INVISIBLE (1175 725);
FORCEPROP 1 LAST COMMENT_BODY TRUE
J 2
(1545 755);
DISPLAY 0.872340 (1545 755);
PAINT GREEN (1545 755);
DISPLAY INVISIBLE (1545 755);
FORCEPROP 2 LAST PATH I65
J 0
(1225 900);
DISPLAY 0.680851 (1225 900);
DISPLAY INVISIBLE (1225 900);
FORCEADD OFFPAGE..2
R 2
(1500 950);
FORCEPROP 2 LAST $XR0 126 
J 0
(1245 950);
DISPLAY 0.638298 (1245 950);
PAINT MONO (1245 950);
FORCEPROP 2 LAST CDS_LIB standard
J 0
(1500 950);
DISPLAY INVISIBLE (1500 950);
FORCEPROP 1 LAST OFFPAGE TRUE
J 2
(1175 825);
DISPLAY 0.872340 (1175 825);
PAINT AQUA (1175 825);
DISPLAY INVISIBLE (1175 825);
FORCEPROP 1 LAST COMMENT_BODY TRUE
J 2
(1545 855);
DISPLAY 0.872340 (1545 855);
PAINT GREEN (1545 855);
DISPLAY INVISIBLE (1545 855);
FORCEPROP 2 LAST PATH I66
J 0
(1225 1000);
DISPLAY 0.680851 (1225 1000);
DISPLAY INVISIBLE (1225 1000);
FORCEADD OFFPAGE..2
R 2
(1500 1100);
FORCEPROP 2 LAST $XR0 127 
J 0
(1245 1100);
DISPLAY 0.638298 (1245 1100);
PAINT MONO (1245 1100);
FORCEPROP 2 LAST CDS_LIB standard
J 0
(1500 1100);
DISPLAY INVISIBLE (1500 1100);
FORCEPROP 1 LAST OFFPAGE TRUE
J 2
(1175 975);
DISPLAY 0.872340 (1175 975);
PAINT AQUA (1175 975);
DISPLAY INVISIBLE (1175 975);
FORCEPROP 1 LAST COMMENT_BODY TRUE
J 2
(1545 1005);
DISPLAY 0.872340 (1545 1005);
PAINT GREEN (1545 1005);
DISPLAY INVISIBLE (1545 1005);
FORCEPROP 2 LAST PATH I67
J 0
(1225 1150);
DISPLAY 0.680851 (1225 1150);
DISPLAY INVISIBLE (1225 1150);
FORCEADD OFFPAGE..1
(1500 1200);
FORCEPROP 2 LAST $XR0 353 
J 0
(1248 1200);
DISPLAY 0.638298 (1248 1200);
PAINT MONO (1248 1200);
FORCEPROP 2 LAST CDS_LIB standard
J 0
(1500 1200);
DISPLAY INVISIBLE (1500 1200);
FORCEPROP 1 LAST OFFPAGE TRUE
J 0
(1825 1075);
DISPLAY 0.872340 (1825 1075);
PAINT AQUA (1825 1075);
DISPLAY INVISIBLE (1825 1075);
FORCEPROP 1 LAST COMMENT_BODY TRUE
J 0
(1625 1100);
DISPLAY 0.872340 (1625 1100);
PAINT GREEN (1625 1100);
DISPLAY INVISIBLE (1625 1100);
FORCEPROP 2 LAST PATH I68
J 0
(1250 1250);
DISPLAY 0.680851 (1250 1250);
DISPLAY INVISIBLE (1250 1250);
FORCEADD OFFPAGE..1
(1500 1250);
FORCEPROP 2 LAST $XR0 353 
J 0
(1248 1250);
DISPLAY 0.638298 (1248 1250);
PAINT MONO (1248 1250);
FORCEPROP 2 LAST CDS_LIB standard
J 0
(1500 1250);
DISPLAY INVISIBLE (1500 1250);
FORCEPROP 1 LAST OFFPAGE TRUE
J 0
(1825 1125);
DISPLAY 0.872340 (1825 1125);
PAINT AQUA (1825 1125);
DISPLAY INVISIBLE (1825 1125);
FORCEPROP 1 LAST COMMENT_BODY TRUE
J 0
(1625 1150);
DISPLAY 0.872340 (1625 1150);
PAINT GREEN (1625 1150);
DISPLAY INVISIBLE (1625 1150);
FORCEPROP 2 LAST PATH I69
J 0
(1250 1300);
DISPLAY 0.680851 (1250 1300);
DISPLAY INVISIBLE (1250 1300);
FORCEADD OFFPAGE..2
R 2
(-3250 -800);
FORCEPROP 2 LAST $XR0 341 
J 0
(-3505 -800);
DISPLAY 0.638298 (-3505 -800);
PAINT MONO (-3505 -800);
FORCEPROP 2 LAST CDS_LIB standard
J 0
(-3250 -800);
DISPLAY INVISIBLE (-3250 -800);
FORCEPROP 1 LAST OFFPAGE TRUE
J 2
(-3575 -925);
DISPLAY 0.872340 (-3575 -925);
PAINT AQUA (-3575 -925);
DISPLAY INVISIBLE (-3575 -925);
FORCEPROP 1 LAST COMMENT_BODY TRUE
J 2
(-3205 -895);
DISPLAY 0.872340 (-3205 -895);
PAINT GREEN (-3205 -895);
DISPLAY INVISIBLE (-3205 -895);
FORCEPROP 2 LAST PATH I7
J 0
(-3525 -750);
DISPLAY 0.680851 (-3525 -750);
DISPLAY INVISIBLE (-3525 -750);
FORCEADD OFFPAGE..1
(1500 1350);
FORCEPROP 2 LAST $XR0 342 
J 0
(1248 1350);
DISPLAY 0.638298 (1248 1350);
PAINT MONO (1248 1350);
FORCEPROP 2 LAST CDS_LIB standard
J 0
(1500 1350);
DISPLAY INVISIBLE (1500 1350);
FORCEPROP 1 LAST OFFPAGE TRUE
J 0
(1825 1225);
DISPLAY 0.872340 (1825 1225);
PAINT AQUA (1825 1225);
DISPLAY INVISIBLE (1825 1225);
FORCEPROP 1 LAST COMMENT_BODY TRUE
J 0
(1625 1250);
DISPLAY 0.872340 (1625 1250);
PAINT GREEN (1625 1250);
DISPLAY INVISIBLE (1625 1250);
FORCEPROP 2 LAST PATH I70
J 0
(1225 1400);
DISPLAY 0.680851 (1225 1400);
DISPLAY INVISIBLE (1225 1400);
FORCEADD OFFPAGE..1
(1500 1400);
FORCEPROP 2 LAST $XR0 342 
J 0
(1248 1400);
DISPLAY 0.638298 (1248 1400);
PAINT MONO (1248 1400);
FORCEPROP 2 LAST CDS_LIB standard
J 0
(1500 1400);
DISPLAY INVISIBLE (1500 1400);
FORCEPROP 1 LAST OFFPAGE TRUE
J 0
(1825 1275);
DISPLAY 0.872340 (1825 1275);
PAINT AQUA (1825 1275);
DISPLAY INVISIBLE (1825 1275);
FORCEPROP 1 LAST COMMENT_BODY TRUE
J 0
(1625 1300);
DISPLAY 0.872340 (1625 1300);
PAINT GREEN (1625 1300);
DISPLAY INVISIBLE (1625 1300);
FORCEPROP 2 LAST PATH I71
J 0
(1225 1450);
DISPLAY 0.680851 (1225 1450);
DISPLAY INVISIBLE (1225 1450);
FORCEADD OFFPAGE..2
R 2
(1500 1550);
FORCEPROP 2 LAST $XR0 352 
J 0
(1245 1550);
DISPLAY 0.638298 (1245 1550);
PAINT MONO (1245 1550);
FORCEPROP 2 LAST CDS_LIB standard
J 0
(1500 1550);
DISPLAY INVISIBLE (1500 1550);
FORCEPROP 1 LAST OFFPAGE TRUE
J 2
(1175 1425);
DISPLAY 0.872340 (1175 1425);
PAINT AQUA (1175 1425);
DISPLAY INVISIBLE (1175 1425);
FORCEPROP 1 LAST COMMENT_BODY TRUE
J 2
(1545 1455);
DISPLAY 0.872340 (1545 1455);
PAINT GREEN (1545 1455);
DISPLAY INVISIBLE (1545 1455);
FORCEPROP 2 LAST PATH I72
J 0
(1225 1600);
DISPLAY 0.680851 (1225 1600);
DISPLAY INVISIBLE (1225 1600);
FORCEADD OFFPAGE..5
(1500 1500);
FORCEPROP 2 LAST $XR0 352 
J 0
(1245 1500);
DISPLAY 0.638298 (1245 1500);
PAINT MONO (1245 1500);
FORCEPROP 2 LAST CDS_LIB standard
J 0
(1500 1500);
DISPLAY INVISIBLE (1500 1500);
FORCEPROP 1 LAST OFFPAGE TRUE
J 0
(1825 1375);
DISPLAY 0.872340 (1825 1375);
PAINT AQUA (1825 1375);
DISPLAY INVISIBLE (1825 1375);
FORCEPROP 1 LAST COMMENT_BODY TRUE
J 0
(1600 1425);
DISPLAY 1.170213 (1600 1425);
PAINT GREEN (1600 1425);
DISPLAY INVISIBLE (1600 1425);
FORCEPROP 2 LAST PATH I73
J 0
(1225 1550);
DISPLAY 0.680851 (1225 1550);
DISPLAY INVISIBLE (1225 1550);
FORCEADD OFFPAGE..2
R 2
(1500 1700);
FORCEPROP 2 LAST $XR0 341 
J 0
(1245 1700);
DISPLAY 0.638298 (1245 1700);
PAINT MONO (1245 1700);
FORCEPROP 2 LAST CDS_LIB standard
J 0
(1500 1700);
DISPLAY INVISIBLE (1500 1700);
FORCEPROP 1 LAST OFFPAGE TRUE
J 2
(1175 1575);
DISPLAY 0.872340 (1175 1575);
PAINT AQUA (1175 1575);
DISPLAY INVISIBLE (1175 1575);
FORCEPROP 1 LAST COMMENT_BODY TRUE
J 2
(1545 1605);
DISPLAY 0.872340 (1545 1605);
PAINT GREEN (1545 1605);
DISPLAY INVISIBLE (1545 1605);
FORCEPROP 2 LAST PATH I74
J 0
(1225 1750);
DISPLAY 0.680851 (1225 1750);
DISPLAY INVISIBLE (1225 1750);
FORCEADD OFFPAGE..5
(1500 1650);
FORCEPROP 2 LAST $XR0 341 
J 0
(1245 1650);
DISPLAY 0.638298 (1245 1650);
PAINT MONO (1245 1650);
FORCEPROP 2 LAST CDS_LIB standard
J 0
(1500 1650);
DISPLAY INVISIBLE (1500 1650);
FORCEPROP 1 LAST OFFPAGE TRUE
J 0
(1825 1525);
DISPLAY 0.872340 (1825 1525);
PAINT AQUA (1825 1525);
DISPLAY INVISIBLE (1825 1525);
FORCEPROP 1 LAST COMMENT_BODY TRUE
J 0
(1600 1575);
DISPLAY 1.170213 (1600 1575);
PAINT GREEN (1600 1575);
DISPLAY INVISIBLE (1600 1575);
FORCEPROP 2 LAST PATH I75
J 0
(1225 1700);
DISPLAY 0.680851 (1225 1700);
DISPLAY INVISIBLE (1225 1700);
FORCEADD CONN112_10137002101LF..2
(3725 250);
FORCEPROP 1 LAST LOCATION J110
J 0
(2975 2075);
DISPLAY 0.723404 (2975 2075);
PAINT GREEN (2975 2075);
FORCEPROP 0 LAST $SEC 2
J 0
(2975 2200);
DISPLAY 0.680851 (2975 2200);
PAINT MONO (2975 2200);
DISPLAY INVISIBLE (2975 2200);
FORCEPROP 0 LAST CDS_SEC 2
J 0
(2975 2200);
DISPLAY 1.021277 (2975 2200);
DISPLAY INVISIBLE (2975 2200);
FORCEPROP 0 LASTPIN (2800 -650) $PN A1
J 2
(2790 -640);
DISPLAY 0.680851 (2790 -640);
PAINT MONO (2790 -640);
FORCEPROP 0 LASTPIN (2800 150) $PN A2
J 2
(2790 160);
DISPLAY 0.680851 (2790 160);
PAINT MONO (2790 160);
FORCEPROP 0 LASTPIN (2800 950) $PN A3
J 2
(2790 960);
DISPLAY 0.680851 (2790 960);
PAINT MONO (2790 960);
FORCEPROP 0 LASTPIN (2800 1750) $PN A4
J 2
(2790 1760);
DISPLAY 0.680851 (2790 1760);
PAINT MONO (2790 1760);
FORCEPROP 0 LASTPIN (2800 -700) $PN B1
J 2
(2790 -690);
DISPLAY 0.680851 (2790 -690);
PAINT MONO (2790 -690);
FORCEPROP 0 LASTPIN (2800 100) $PN B2
J 2
(2790 110);
DISPLAY 0.680851 (2790 110);
PAINT MONO (2790 110);
FORCEPROP 0 LASTPIN (2800 900) $PN B3
J 2
(2790 910);
DISPLAY 0.680851 (2790 910);
PAINT MONO (2790 910);
FORCEPROP 0 LASTPIN (2800 1700) $PN B4
J 2
(2790 1710);
DISPLAY 0.680851 (2790 1710);
PAINT MONO (2790 1710);
FORCEPROP 0 LASTPIN (2800 -750) $PN C1
J 2
(2790 -740);
DISPLAY 0.680851 (2790 -740);
PAINT MONO (2790 -740);
FORCEPROP 0 LASTPIN (2800 50) $PN C2
J 2
(2790 60);
DISPLAY 0.680851 (2790 60);
PAINT MONO (2790 60);
FORCEPROP 0 LASTPIN (2800 850) $PN C3
J 2
(2790 860);
DISPLAY 0.680851 (2790 860);
PAINT MONO (2790 860);
FORCEPROP 0 LASTPIN (2800 1650) $PN C4
J 2
(2790 1660);
DISPLAY 0.680851 (2790 1660);
PAINT MONO (2790 1660);
FORCEPROP 0 LASTPIN (2800 -800) $PN D1
J 2
(2790 -790);
DISPLAY 0.680851 (2790 -790);
PAINT MONO (2790 -790);
FORCEPROP 0 LASTPIN (2800 0) $PN D2
J 2
(2790 10);
DISPLAY 0.680851 (2790 10);
PAINT MONO (2790 10);
FORCEPROP 0 LASTPIN (2800 800) $PN D3
J 2
(2790 810);
DISPLAY 0.680851 (2790 810);
PAINT MONO (2790 810);
FORCEPROP 0 LASTPIN (2800 1600) $PN D4
J 2
(2790 1610);
DISPLAY 0.680851 (2790 1610);
PAINT MONO (2790 1610);
FORCEPROP 0 LASTPIN (2800 -850) $PN E1
J 2
(2790 -840);
DISPLAY 0.680851 (2790 -840);
PAINT MONO (2790 -840);
FORCEPROP 0 LASTPIN (2800 -50) $PN E2
J 2
(2790 -40);
DISPLAY 0.680851 (2790 -40);
PAINT MONO (2790 -40);
FORCEPROP 0 LASTPIN (2800 750) $PN E3
J 2
(2790 760);
DISPLAY 0.680851 (2790 760);
PAINT MONO (2790 760);
FORCEPROP 0 LASTPIN (2800 1550) $PN E4
J 2
(2790 1560);
DISPLAY 0.680851 (2790 1560);
PAINT MONO (2790 1560);
FORCEPROP 0 LASTPIN (2800 -900) $PN F1
J 2
(2790 -890);
DISPLAY 0.680851 (2790 -890);
PAINT MONO (2790 -890);
FORCEPROP 0 LASTPIN (2800 -100) $PN F2
J 2
(2790 -90);
DISPLAY 0.680851 (2790 -90);
PAINT MONO (2790 -90);
FORCEPROP 0 LASTPIN (2800 700) $PN F3
J 2
(2790 710);
DISPLAY 0.680851 (2790 710);
PAINT MONO (2790 710);
FORCEPROP 0 LASTPIN (2800 1500) $PN F4
J 2
(2790 1510);
DISPLAY 0.680851 (2790 1510);
PAINT MONO (2790 1510);
FORCEPROP 0 LASTPIN (2800 -950) $PN G1
J 2
(2790 -940);
DISPLAY 0.680851 (2790 -940);
PAINT MONO (2790 -940);
FORCEPROP 0 LASTPIN (2800 -150) $PN G2
J 2
(2790 -140);
DISPLAY 0.680851 (2790 -140);
PAINT MONO (2790 -140);
FORCEPROP 0 LASTPIN (2800 650) $PN G3
J 2
(2790 660);
DISPLAY 0.680851 (2790 660);
PAINT MONO (2790 660);
FORCEPROP 0 LASTPIN (2800 1450) $PN G4
J 2
(2790 1460);
DISPLAY 0.680851 (2790 1460);
PAINT MONO (2790 1460);
FORCEPROP 0 LASTPIN (2800 -1000) $PN H1
J 2
(2790 -990);
DISPLAY 0.680851 (2790 -990);
PAINT MONO (2790 -990);
FORCEPROP 0 LASTPIN (2800 -200) $PN H2
J 2
(2790 -190);
DISPLAY 0.680851 (2790 -190);
PAINT MONO (2790 -190);
FORCEPROP 0 LASTPIN (2800 600) $PN H3
J 2
(2790 610);
DISPLAY 0.680851 (2790 610);
PAINT MONO (2790 610);
FORCEPROP 0 LASTPIN (2800 1400) $PN H4
J 2
(2790 1410);
DISPLAY 0.680851 (2790 1410);
PAINT MONO (2790 1410);
FORCEPROP 0 LASTPIN (2800 -1050) $PN I1
J 2
(2790 -1040);
DISPLAY 0.680851 (2790 -1040);
PAINT MONO (2790 -1040);
FORCEPROP 0 LASTPIN (2800 -250) $PN I2
J 2
(2790 -240);
DISPLAY 0.680851 (2790 -240);
PAINT MONO (2790 -240);
FORCEPROP 0 LASTPIN (2800 550) $PN I3
J 2
(2790 560);
DISPLAY 0.680851 (2790 560);
PAINT MONO (2790 560);
FORCEPROP 0 LASTPIN (2800 1350) $PN I4
J 2
(2790 1360);
DISPLAY 0.680851 (2790 1360);
PAINT MONO (2790 1360);
FORCEPROP 0 LASTPIN (2800 -1100) $PN J1
J 2
(2790 -1090);
DISPLAY 0.680851 (2790 -1090);
PAINT MONO (2790 -1090);
FORCEPROP 0 LASTPIN (2800 -300) $PN J2
J 2
(2790 -290);
DISPLAY 0.680851 (2790 -290);
PAINT MONO (2790 -290);
FORCEPROP 0 LASTPIN (2800 500) $PN J3
J 2
(2790 510);
DISPLAY 0.680851 (2790 510);
PAINT MONO (2790 510);
FORCEPROP 0 LASTPIN (2800 1300) $PN J4
J 2
(2790 1310);
DISPLAY 0.680851 (2790 1310);
PAINT MONO (2790 1310);
FORCEPROP 0 LASTPIN (2800 -1150) $PN K1
J 2
(2790 -1140);
DISPLAY 0.680851 (2790 -1140);
PAINT MONO (2790 -1140);
FORCEPROP 0 LASTPIN (2800 -350) $PN K2
J 2
(2790 -340);
DISPLAY 0.680851 (2790 -340);
PAINT MONO (2790 -340);
FORCEPROP 0 LASTPIN (2800 450) $PN K3
J 2
(2790 460);
DISPLAY 0.680851 (2790 460);
PAINT MONO (2790 460);
FORCEPROP 0 LASTPIN (2800 1250) $PN K4
J 2
(2790 1260);
DISPLAY 0.680851 (2790 1260);
PAINT MONO (2790 1260);
FORCEPROP 0 LASTPIN (2800 -1200) $PN L1
J 2
(2790 -1190);
DISPLAY 0.680851 (2790 -1190);
PAINT MONO (2790 -1190);
FORCEPROP 0 LASTPIN (2800 -400) $PN L2
J 2
(2790 -390);
DISPLAY 0.680851 (2790 -390);
PAINT MONO (2790 -390);
FORCEPROP 0 LASTPIN (2800 400) $PN L3
J 2
(2790 410);
DISPLAY 0.680851 (2790 410);
PAINT MONO (2790 410);
FORCEPROP 0 LASTPIN (2800 1200) $PN L4
J 2
(2790 1210);
DISPLAY 0.680851 (2790 1210);
PAINT MONO (2790 1210);
FORCEPROP 0 LASTPIN (2800 -1250) $PN M1
J 2
(2790 -1240);
DISPLAY 0.680851 (2790 -1240);
PAINT MONO (2790 -1240);
FORCEPROP 0 LASTPIN (2800 -450) $PN M2
J 2
(2790 -440);
DISPLAY 0.680851 (2790 -440);
PAINT MONO (2790 -440);
FORCEPROP 0 LASTPIN (2800 350) $PN M3
J 2
(2790 360);
DISPLAY 0.680851 (2790 360);
PAINT MONO (2790 360);
FORCEPROP 0 LASTPIN (2800 1150) $PN M4
J 2
(2790 1160);
DISPLAY 0.680851 (2790 1160);
PAINT MONO (2790 1160);
FORCEPROP 0 LASTPIN (2800 -1300) $PN N1
J 2
(2790 -1290);
DISPLAY 0.680851 (2790 -1290);
PAINT MONO (2790 -1290);
FORCEPROP 0 LASTPIN (2800 -500) $PN N2
J 2
(2790 -490);
DISPLAY 0.680851 (2790 -490);
PAINT MONO (2790 -490);
FORCEPROP 0 LASTPIN (2800 300) $PN N3
J 2
(2790 310);
DISPLAY 0.680851 (2790 310);
PAINT MONO (2790 310);
FORCEPROP 0 LASTPIN (2800 1100) $PN N4
J 2
(2790 1110);
DISPLAY 0.680851 (2790 1110);
PAINT MONO (2790 1110);
FORCEPROP 2 LAST PART_TYPE THLF
J 0
(2975 2150);
DISPLAY 1.021277 (2975 2150);
FORCEPROP 1 LAST MATERIAL IO
J 0
(2983 1963);
DISPLAY 0.723404 (2983 1963);
PAINT GREEN (2983 1963);
FORCEPROP 1 LAST CDS_LMAN_SYM_OUTLINE -775,1650,775,-1650
J 0
(3725 250);
DISPLAY 0.468085 (3725 250);
PAINT GREEN (3725 250);
DISPLAY INVISIBLE (3725 250);
FORCEPROP 1 LAST NEEDS_NO_SIZE TRUE
J 0
(3725 250);
DISPLAY 0.723404 (3725 250);
PAINT GREEN (3725 250);
DISPLAY INVISIBLE (3725 250);
FORCEPROP 2 LAST CDS_LIB pure_quanta
J 0
(3725 250);
DISPLAY INVISIBLE (3725 250);
FORCEPROP 0 LAST VALUE CONN112_10137002-101LF
J 0
(2975 2150);
DISPLAY 1.021277 (2975 2150);
DISPLAY INVISIBLE (2975 2150);
FORCEPROP 1 LAST PATH I76
J 0
(3725 250);
DISPLAY 0.723404 (3725 250);
PAINT GREEN (3725 250);
DISPLAY INVISIBLE (3725 250);
FORCEPROP 1 LAST PART_NUMBER DFHSB2FR012
J 0
(2975 2025);
DISPLAY 0.723404 (2975 2025);
PAINT GREEN (2975 2025);
DISPLAY INVISIBLE (2975 2025);
FORCEADD OFFPAGE..5
(-3250 -850);
FORCEPROP 2 LAST $XR0 341 
J 0
(-3505 -850);
DISPLAY 0.638298 (-3505 -850);
PAINT MONO (-3505 -850);
FORCEPROP 2 LAST CDS_LIB standard
J 0
(-3250 -850);
DISPLAY INVISIBLE (-3250 -850);
FORCEPROP 1 LAST OFFPAGE TRUE
J 0
(-2925 -975);
DISPLAY 0.872340 (-2925 -975);
PAINT AQUA (-2925 -975);
DISPLAY INVISIBLE (-2925 -975);
FORCEPROP 1 LAST COMMENT_BODY TRUE
J 0
(-3150 -925);
DISPLAY 1.170213 (-3150 -925);
PAINT GREEN (-3150 -925);
DISPLAY INVISIBLE (-3150 -925);
FORCEPROP 2 LAST PATH I8
J 0
(-3525 -800);
DISPLAY 0.680851 (-3525 -800);
DISPLAY INVISIBLE (-3525 -800);
FORCEADD OFFPAGE..5
(-3250 -700);
FORCEPROP 2 LAST $XR0 126 
J 0
(-3505 -700);
DISPLAY 0.638298 (-3505 -700);
PAINT MONO (-3505 -700);
FORCEPROP 2 LAST CDS_LIB standard
J 0
(-3250 -700);
DISPLAY INVISIBLE (-3250 -700);
FORCEPROP 1 LAST OFFPAGE TRUE
J 0
(-2925 -825);
DISPLAY 0.872340 (-2925 -825);
PAINT AQUA (-2925 -825);
DISPLAY INVISIBLE (-2925 -825);
FORCEPROP 1 LAST COMMENT_BODY TRUE
J 0
(-3150 -775);
DISPLAY 1.170213 (-3150 -775);
PAINT GREEN (-3150 -775);
DISPLAY INVISIBLE (-3150 -775);
FORCEPROP 2 LAST PATH I9
J 0
(-3525 -650);
DISPLAY 0.680851 (-3525 -650);
DISPLAY INVISIBLE (-3525 -650);
FORCEADD QUANTA_TITLE_BLOCK_C..1
(4675 -3325);
FORCEPROP 0 LAST CDS_CON_LAST_MODIFIED Thu Sep 14 16:12:59 2023
J 0
(2790 -3310);
PAINT MONO (2790 -3310);
DISPLAY INVISIBLE (2790 -3310);
FORCEPROP 2 LAST CUSTOM_TXT_CDS <XR_PAGE_TITLE>
J 0
(-3215 1925);
DISPLAY 0.638298 (-3215 1925);
PAINT PINK (-3215 1925);
DISPLAY INVISIBLE (-3215 1925);
FORCEPROP 2 LAST CUSTOM_TXT_CDS <CON_LAST_MODIFIED>
J 0
(2800 -3300);
DISPLAY 0.978723 (2800 -3300);
FORCEPROP 2 LAST CUSTOM_TXT_CDS <CON_PAGE_NUM> OF <CON_TOTAL_PAGES>
J 0
(4229 -3307);
DISPLAY 0.978723 (4229 -3307);
FORCEPROP 2 LAST CUSTOM_TXT_CDS <Q_NUMBER>
J 0
(3272 -3222);
DISPLAY 1.212766 (3272 -3222);
FORCEPROP 2 LAST CUSTOM_TXT_CDS <Q_PROJ>
J 0
(2293 -3223);
DISPLAY 1.212766 (2293 -3223);
FORCEPROP 2 LAST CUSTOM_TXT_CDS <NAME_1>
J 0
(1500 -3150);
FORCEPROP 2 LAST CUSTOM_TXT_CDS <NAME_2>
J 0
(1500 -3275);
FORCEPROP 2 LAST CUSTOM_TXT_CDS <Q_REV>
J 0
(4491 -3222);
DISPLAY 1.212766 (4491 -3222);
FORCEPROP 1 LAST Q_TITLE PCIE - CPU1_EXAMAX_P2/P3_X16
J 0
(-4600 -3275);
DISPLAY 1.957447 (-4600 -3275);
PAINT GREEN (-4600 -3275);
FORCEPROP 2 LAST PAGE_BORDER TRUE
J 0
(-3215 1925);
DISPLAY 0.638298 (-3215 1925);
PAINT PINK (-3215 1925);
DISPLAY INVISIBLE (-3215 1925);
FORCEPROP 1 LAST CDS_LMAN_SYM_OUTLINE -9475,6775,100,-125
J 0
(4675 -3325);
DISPLAY 0.468085 (4675 -3325);
PAINT GREEN (4675 -3325);
DISPLAY INVISIBLE (4675 -3325);
FORCEPROP 2 LAST CDS_LIB pure_quanta
J 0
(4675 -3325);
PAINT MONO (4675 -3325);
DISPLAY INVISIBLE (4675 -3325);
FORCEPROP 2 LAST CDS_XR_PAGE_TITLE CR-120 : @T6G_MB_LIB.T6G(SCH_1):PAGE120
J 0
(-3215 1925);
DISPLAY 0.638298 (-3215 1925);
PAINT PINK (-3215 1925);
DISPLAY INVISIBLE (-3215 1925);
FORCEPROP 1 LAST Q_DEPT BU9
J 1
(912 -3276);
DISPLAY 1.957447 (912 -3276);
PAINT GREEN (912 -3276);
DISPLAY INVISIBLE (912 -3276);
FORCEPROP 1 LAST COMMENT_BODY TRUE
J 0
(4687 -3338);
DISPLAY 0.978723 (4687 -3338);
PAINT GREEN (4687 -3338);
DISPLAY INVISIBLE (4687 -3338);
WIRE 16 -1 (2800 -1100)(1550 -1100);
FORCEPROP 2 LAST SIG_NAME P5E_CPU1_P2_TX_BUF_C_DP<0>
J 0
(1665 -1090);
DISPLAY 0.638298 (1665 -1090);
WIRE 16 -1 (2800 -950)(1550 -950);
FORCEPROP 2 LAST SIG_NAME P5E_CPU1_P3_RX_BUF_DP<0>
J 0
(1665 -940);
DISPLAY 0.638298 (1665 -940);
WIRE 16 -1 (2800 -900)(1550 -900);
FORCEPROP 2 LAST SIG_NAME P5E_CPU1_P3_RX_BUF_DN<0>
J 0
(1665 -890);
DISPLAY 0.638298 (1665 -890);
WIRE 16 -1 (2800 -1200)(1550 -1200);
FORCEPROP 2 LAST SIG_NAME P5E_CPU1_P3_TX_BUF_C_DN<0>
J 0
(1665 -1190);
DISPLAY 0.638298 (1665 -1190);
WIRE 16 -1 (2800 -1050)(1550 -1050);
FORCEPROP 2 LAST SIG_NAME P5E_CPU1_P2_TX_BUF_C_DN<0>
J 0
(1665 -1040);
DISPLAY 0.638298 (1665 -1040);
WIRE 16 -1 (2800 1750)(2575 1750);
WIRE 16 -1 (2575 1750)(2575 1600);
WIRE 16 -1 (2800 1600)(2575 1600);
WIRE 16 -1 (2575 1600)(2575 1450);
WIRE 16 -1 (2800 1450)(2575 1450);
WIRE 16 -1 (2575 1450)(2575 1300);
WIRE 16 -1 (2800 1300)(2575 1300);
WIRE 16 -1 (2575 1300)(2575 1150);
WIRE 16 -1 (2800 1150)(2575 1150);
WIRE 16 -1 (2575 1150)(2575 900);
WIRE 16 -1 (2800 900)(2575 900);
WIRE 16 -1 (2575 900)(2575 750);
WIRE 16 -1 (2800 750)(2575 750);
WIRE 16 -1 (2575 750)(2575 600);
WIRE 16 -1 (2800 600)(2575 600);
WIRE 16 -1 (2575 600)(2575 450);
WIRE 16 -1 (2800 450)(2575 450);
WIRE 16 -1 (2575 450)(2575 300);
WIRE 16 -1 (2800 300)(2575 300);
WIRE 16 -1 (2575 300)(2575 150);
WIRE 16 -1 (2800 150)(2575 150);
WIRE 16 -1 (2575 150)(2575 0);
WIRE 16 -1 (2800 0)(2575 0);
WIRE 16 -1 (2575 0)(2575 -150);
WIRE 16 -1 (2800 -150)(2575 -150);
WIRE 16 -1 (2575 -150)(2575 -300);
WIRE 16 -1 (2800 -300)(2575 -300);
WIRE 16 -1 (2575 -300)(2575 -450);
WIRE 16 -1 (2800 -450)(2575 -450);
WIRE 16 -1 (2575 -450)(2575 -700);
WIRE 16 -1 (2800 -700)(2575 -700);
WIRE 16 -1 (2575 -700)(2575 -850);
WIRE 16 -1 (2800 -850)(2575 -850);
WIRE 16 -1 (2575 -850)(2575 -1000);
WIRE 16 -1 (2800 -1000)(2575 -1000);
WIRE 16 -1 (2575 -1000)(2575 -1150);
WIRE 16 -1 (2800 -1150)(2575 -1150);
WIRE 16 -1 (2575 -1150)(2575 -1300);
WIRE 16 -1 (2800 -1300)(2575 -1300);
WIRE 16 -1 (2575 -1300)(2575 -1650);
WIRE 16 -1 (2800 -800)(1550 -800);
FORCEPROP 2 LAST SIG_NAME P5E_CPU1_P2_RX_BUF_DP<0>
J 0
(1665 -790);
DISPLAY 0.638298 (1665 -790);
WIRE 16 -1 (2800 -500)(1550 -500);
FORCEPROP 2 LAST SIG_NAME GPU_FPGA_BOOT_EN_BUF
J 0
(1665 -490);
DISPLAY 0.638298 (1665 -490);
WIRE 16 -1 (2800 -650)(1550 -650);
FORCEPROP 2 LAST SIG_NAME GPU_FPGA_EROT_RECOV_BUF_N
J 0
(1665 -640);
DISPLAY 0.638298 (1665 -640);
WIRE 16 -1 (2800 -350)(1550 -350);
FORCEPROP 2 LAST SIG_NAME P5E_CPU1_P3_TX_BUF_C_DN<1>
J 0
(1665 -340);
DISPLAY 0.638298 (1665 -340);
WIRE 16 -1 (2800 -400)(1550 -400);
FORCEPROP 2 LAST SIG_NAME P5E_CPU1_P3_TX_BUF_C_DP<1>
J 0
(1665 -390);
DISPLAY 0.638298 (1665 -390);
WIRE 16 -1 (2800 -250)(1550 -250);
FORCEPROP 2 LAST SIG_NAME P5E_CPU1_P2_TX_BUF_C_DP<1>
J 0
(1665 -240);
DISPLAY 0.638298 (1665 -240);
WIRE 16 -1 (2800 -200)(1550 -200);
FORCEPROP 2 LAST SIG_NAME P5E_CPU1_P2_TX_BUF_C_DN<1>
J 0
(1665 -190);
DISPLAY 0.638298 (1665 -190);
WIRE 16 -1 (2800 -100)(1550 -100);
FORCEPROP 2 LAST SIG_NAME P5E_CPU1_P3_RX_BUF_DP<1>
J 0
(1665 -90);
DISPLAY 0.638298 (1665 -90);
WIRE 16 -1 (2800 -50)(1550 -50);
FORCEPROP 2 LAST SIG_NAME P5E_CPU1_P3_RX_BUF_DN<1>
J 0
(1665 -40);
DISPLAY 0.638298 (1665 -40);
WIRE 16 -1 (2800 50)(1550 50);
FORCEPROP 2 LAST SIG_NAME P5E_CPU1_P2_RX_BUF_DP<1>
J 0
(1665 60);
DISPLAY 0.638298 (1665 60);
WIRE 16 -1 (2800 100)(1550 100);
FORCEPROP 2 LAST SIG_NAME P5E_CPU1_P2_RX_BUF_DN<1>
J 0
(1665 110);
DISPLAY 0.638298 (1665 110);
WIRE 16 -1 (2800 350)(1550 350);
FORCEPROP 2 LAST SIG_NAME P5E_CPU1_P3_TX_BUF_C_DP<2>
J 0
(1665 360);
DISPLAY 0.638298 (1665 360);
WIRE 16 -1 (2800 400)(1550 400);
FORCEPROP 2 LAST SIG_NAME P5E_CPU1_P3_TX_BUF_C_DN<2>
J 0
(1665 410);
DISPLAY 0.638298 (1665 410);
WIRE 16 -1 (2800 500)(1550 500);
FORCEPROP 2 LAST SIG_NAME P5E_CPU1_P2_TX_BUF_C_DP<2>
J 0
(1665 510);
DISPLAY 0.638298 (1665 510);
WIRE 16 -1 (2800 550)(1550 550);
FORCEPROP 2 LAST SIG_NAME P5E_CPU1_P2_TX_BUF_C_DN<2>
J 0
(1665 560);
DISPLAY 0.638298 (1665 560);
WIRE 16 -1 (2800 650)(1550 650);
FORCEPROP 2 LAST SIG_NAME P5E_CPU1_P3_RX_BUF_DP<2>
J 0
(1665 660);
DISPLAY 0.638298 (1665 660);
WIRE 16 -1 (2800 700)(1550 700);
FORCEPROP 2 LAST SIG_NAME P5E_CPU1_P3_RX_BUF_DN<2>
J 0
(1665 710);
DISPLAY 0.638298 (1665 710);
WIRE 16 -1 (2800 1100)(1550 1100);
FORCEPROP 2 LAST SIG_NAME FM_SMB_1_ALERT_GPU_N
J 0
(1665 1110);
DISPLAY 0.638298 (1665 1110);
WIRE 16 -1 (2800 950)(1550 950);
FORCEPROP 2 LAST SIG_NAME GPU_HMC_PRSNT_N
J 0
(1665 960);
DISPLAY 0.638298 (1665 960);
WIRE 16 -1 (2800 1200)(1550 1200);
FORCEPROP 2 LAST SIG_NAME P5E_CPU1_P3_TX_BUF_C_DP<3>
J 0
(1665 1210);
DISPLAY 0.638298 (1665 1210);
WIRE 16 -1 (2800 1250)(1550 1250);
FORCEPROP 2 LAST SIG_NAME P5E_CPU1_P3_TX_BUF_C_DN<3>
J 0
(1665 1260);
DISPLAY 0.638298 (1665 1260);
WIRE 16 -1 (2800 1350)(1550 1350);
FORCEPROP 2 LAST SIG_NAME P5E_CPU1_P2_TX_BUF_C_DP<3>
J 0
(1665 1360);
DISPLAY 0.638298 (1665 1360);
WIRE 16 -1 (2800 1400)(1550 1400);
FORCEPROP 2 LAST SIG_NAME P5E_CPU1_P2_TX_BUF_C_DN<3>
J 0
(1665 1410);
DISPLAY 0.638298 (1665 1410);
WIRE 16 -1 (2800 1500)(1550 1500);
FORCEPROP 2 LAST SIG_NAME P5E_CPU1_P3_RX_BUF_DP<3>
J 0
(1665 1510);
DISPLAY 0.638298 (1665 1510);
WIRE 16 -1 (2800 1550)(1550 1550);
FORCEPROP 2 LAST SIG_NAME P5E_CPU1_P3_RX_BUF_DN<3>
J 0
(1665 1560);
DISPLAY 0.638298 (1665 1560);
WIRE 16 -1 (-1975 -1100)(-3200 -1100);
FORCEPROP 2 LAST SIG_NAME P5E_CPU1_P2_TX_BUF_C_DN<4>
J 0
(-3085 -1090);
DISPLAY 0.638298 (-3085 -1090);
WIRE 16 -1 (-1975 1700)(-2150 1700);
WIRE 16 -1 (-2150 1700)(-2150 1550);
WIRE 16 -1 (-1975 1550)(-2150 1550);
WIRE 16 -1 (-2150 1550)(-2150 1400);
WIRE 16 -1 (-1975 1400)(-2150 1400);
WIRE 16 -1 (-2150 1400)(-2150 1250);
WIRE 16 -1 (-1975 1250)(-2150 1250);
WIRE 16 -1 (-2150 1250)(-2150 1100);
WIRE 16 -1 (-1975 1100)(-2150 1100);
WIRE 16 -1 (-2150 1100)(-2150 850);
WIRE 16 -1 (-1975 850)(-2150 850);
WIRE 16 -1 (-2150 850)(-2150 700);
WIRE 16 -1 (-1975 700)(-2150 700);
WIRE 16 -1 (-2150 700)(-2150 550);
WIRE 16 -1 (-1975 550)(-2150 550);
WIRE 16 -1 (-2150 550)(-2150 400);
WIRE 16 -1 (-1975 400)(-2150 400);
WIRE 16 -1 (-2150 400)(-2150 250);
WIRE 16 -1 (-1975 250)(-2150 250);
WIRE 16 -1 (-2150 250)(-2150 100);
WIRE 16 -1 (-1975 100)(-2150 100);
WIRE 16 -1 (-2150 100)(-2150 -50);
WIRE 16 -1 (-1975 -50)(-2150 -50);
WIRE 16 -1 (-2150 -50)(-2150 -200);
WIRE 16 -1 (-1975 -200)(-2150 -200);
WIRE 16 -1 (-2150 -200)(-2150 -350);
WIRE 16 -1 (-1975 -350)(-2150 -350);
WIRE 16 -1 (-2150 -350)(-2150 -500);
WIRE 16 -1 (-1975 -500)(-2150 -500);
WIRE 16 -1 (-2150 -500)(-2150 -750);
WIRE 16 -1 (-1975 -750)(-2150 -750);
WIRE 16 -1 (-2150 -900)(-2150 -750);
WIRE 16 -1 (-1975 -900)(-2150 -900);
WIRE 16 -1 (-2150 -1050)(-2150 -900);
WIRE 16 -1 (-1975 -1050)(-2150 -1050);
WIRE 16 -1 (-2150 -1050)(-2150 -1200);
WIRE 16 -1 (-1975 -1200)(-2150 -1200);
WIRE 16 -1 (-2150 -1200)(-2150 -1350);
WIRE 16 -1 (-1975 -1350)(-2150 -1350);
WIRE 16 -1 (-2150 -1350)(-2150 -1650);
WIRE 16 -1 (-1975 -1150)(-3200 -1150);
FORCEPROP 2 LAST SIG_NAME P5E_CPU1_P2_TX_BUF_C_DP<4>
J 0
(-3085 -1140);
DISPLAY 0.638298 (-3085 -1140);
WIRE 16 -1 (-1975 -1000)(-3200 -1000);
FORCEPROP 2 LAST SIG_NAME P5E_CPU1_P3_RX_BUF_DP<4>
J 0
(-3085 -990);
DISPLAY 0.638298 (-3085 -990);
WIRE 16 -1 (-1975 -850)(-3200 -850);
FORCEPROP 2 LAST SIG_NAME P5E_CPU1_P2_RX_BUF_DP<4>
J 0
(-3085 -840);
DISPLAY 0.638298 (-3085 -840);
WIRE 16 -1 (-1975 -800)(-3200 -800);
FORCEPROP 2 LAST SIG_NAME P5E_CPU1_P2_RX_BUF_DN<4>
J 0
(-3085 -790);
DISPLAY 0.638298 (-3085 -790);
WIRE 16 -1 (-1975 -700)(-3200 -700);
FORCEPROP 2 LAST SIG_NAME GPU_BASE_HMC_READY
J 0
(-3085 -690);
DISPLAY 0.638298 (-3085 -690);
WIRE 16 -1 (-1975 -550)(-3200 -550);
FORCEPROP 2 LAST SIG_NAME FM_SMB_2_ALERT_GPU_N
J 0
(-3085 -540);
DISPLAY 0.638298 (-3085 -540);
WIRE 16 -1 (-1975 -450)(-3200 -450);
FORCEPROP 2 LAST SIG_NAME P5E_CPU1_P3_TX_BUF_C_DP<5>
J 0
(-3085 -440);
DISPLAY 0.638298 (-3085 -440);
WIRE 16 -1 (-1975 -300)(-3200 -300);
FORCEPROP 2 LAST SIG_NAME P5E_CPU1_P2_TX_BUF_C_DP<5>
J 0
(-3085 -290);
DISPLAY 0.638298 (-3085 -290);
WIRE 16 -1 (-1975 -150)(-3200 -150);
FORCEPROP 2 LAST SIG_NAME P5E_CPU1_P3_RX_BUF_DP<5>
J 0
(-3085 -140);
DISPLAY 0.638298 (-3085 -140);
WIRE 16 -1 (-1975 -100)(-3200 -100);
FORCEPROP 2 LAST SIG_NAME P5E_CPU1_P3_RX_BUF_DN<5>
J 0
(-3085 -90);
DISPLAY 0.638298 (-3085 -90);
WIRE 16 -1 (-1975 0)(-3200 0);
FORCEPROP 2 LAST SIG_NAME P5E_CPU1_P2_RX_BUF_DP<5>
J 0
(-3085 10);
DISPLAY 0.638298 (-3085 10);
WIRE 16 -1 (-1975 50)(-3200 50);
FORCEPROP 2 LAST SIG_NAME P5E_CPU1_P2_RX_BUF_DN<5>
J 0
(-3085 60);
DISPLAY 0.638298 (-3085 60);
WIRE 16 -1 (-1975 300)(-3200 300);
FORCEPROP 2 LAST SIG_NAME P5E_CPU1_P3_TX_BUF_C_DP<6>
J 0
(-3085 310);
DISPLAY 0.638298 (-3085 310);
WIRE 16 -1 (-1975 350)(-3200 350);
FORCEPROP 2 LAST SIG_NAME P5E_CPU1_P3_TX_BUF_C_DN<6>
J 0
(-3085 360);
DISPLAY 0.638298 (-3085 360);
WIRE 16 -1 (-1975 450)(-3200 450);
FORCEPROP 2 LAST SIG_NAME P5E_CPU1_P2_TX_BUF_C_DP<6>
J 0
(-3085 460);
DISPLAY 0.638298 (-3085 460);
WIRE 16 -1 (-1975 500)(-3200 500);
FORCEPROP 2 LAST SIG_NAME P5E_CPU1_P2_TX_BUF_C_DN<6>
J 0
(-3085 510);
DISPLAY 0.638298 (-3085 510);
WIRE 16 -1 (-1975 600)(-3200 600);
FORCEPROP 2 LAST SIG_NAME P5E_CPU1_P3_RX_BUF_DP<6>
J 0
(-3085 610);
DISPLAY 0.638298 (-3085 610);
WIRE 16 -1 (-1975 650)(-3200 650);
FORCEPROP 2 LAST SIG_NAME P5E_CPU1_P3_RX_BUF_DN<6>
J 0
(-3085 660);
DISPLAY 0.638298 (-3085 660);
WIRE 16 -1 (-1975 750)(-3200 750);
FORCEPROP 2 LAST SIG_NAME P5E_CPU1_P2_RX_BUF_DP<6>
J 0
(-3085 760);
DISPLAY 0.638298 (-3085 760);
WIRE 16 -1 (-1975 800)(-3200 800);
FORCEPROP 2 LAST SIG_NAME P5E_CPU1_P2_RX_BUF_DN<6>
J 0
(-3085 810);
DISPLAY 0.638298 (-3085 810);
WIRE 16 -1 (-1975 900)(-3200 900);
FORCEPROP 2 LAST SIG_NAME GPU_BASE_STBY_EN_BUF
J 0
(-3085 910);
DISPLAY 0.638298 (-3085 910);
WIRE 16 -1 (-1975 1050)(-3200 1050);
FORCEPROP 2 LAST SIG_NAME GPU_FPGA_EROT_RST_BUF_N
J 0
(-3085 1060);
DISPLAY 0.638298 (-3085 1060);
WIRE 16 -1 (-1975 1150)(-3200 1150);
FORCEPROP 2 LAST SIG_NAME P5E_CPU1_P3_TX_BUF_C_DP<7>
J 0
(-3085 1160);
DISPLAY 0.638298 (-3085 1160);
WIRE 16 -1 (-1975 1200)(-3200 1200);
FORCEPROP 2 LAST SIG_NAME P5E_CPU1_P3_TX_BUF_C_DN<7>
J 0
(-3085 1210);
DISPLAY 0.638298 (-3085 1210);
WIRE 16 -1 (-1975 -1250)(-3200 -1250);
FORCEPROP 2 LAST SIG_NAME P5E_CPU1_P3_TX_BUF_C_DN<4>
J 0
(-3085 -1240);
DISPLAY 0.638298 (-3085 -1240);
WIRE 16 -1 (-1975 -1300)(-3200 -1300);
FORCEPROP 2 LAST SIG_NAME P5E_CPU1_P3_TX_BUF_C_DP<4>
J 0
(-3085 -1290);
DISPLAY 0.638298 (-3085 -1290);
WIRE 16 -1 (-1975 -950)(-3200 -950);
FORCEPROP 2 LAST SIG_NAME P5E_CPU1_P3_RX_BUF_DN<4>
J 0
(-3085 -940);
DISPLAY 0.638298 (-3085 -940);
WIRE 16 -1 (-1975 -400)(-3200 -400);
FORCEPROP 2 LAST SIG_NAME P5E_CPU1_P3_TX_BUF_C_DN<5>
J 0
(-3085 -390);
DISPLAY 0.638298 (-3085 -390);
WIRE 16 -1 (-1975 -250)(-3200 -250);
FORCEPROP 2 LAST SIG_NAME P5E_CPU1_P2_TX_BUF_C_DN<5>
J 0
(-3085 -240);
DISPLAY 0.638298 (-3085 -240);
WIRE 16 -1 (-1975 1300)(-3200 1300);
FORCEPROP 2 LAST SIG_NAME P5E_CPU1_P2_TX_BUF_C_DP<7>
J 0
(-3085 1310);
DISPLAY 0.638298 (-3085 1310);
WIRE 16 -1 (-1975 1500)(-3200 1500);
FORCEPROP 2 LAST SIG_NAME P5E_CPU1_P3_RX_BUF_DN<7>
J 0
(-3085 1510);
DISPLAY 0.638298 (-3085 1510);
WIRE 16 -1 (-1975 1450)(-3200 1450);
FORCEPROP 2 LAST SIG_NAME P5E_CPU1_P3_RX_BUF_DP<7>
J 0
(-3085 1460);
DISPLAY 0.638298 (-3085 1460);
WIRE 16 -1 (-1975 1350)(-3200 1350);
FORCEPROP 2 LAST SIG_NAME P5E_CPU1_P2_TX_BUF_C_DN<7>
J 0
(-3085 1360);
DISPLAY 0.638298 (-3085 1360);
WIRE 16 -1 (2800 -750)(1550 -750);
FORCEPROP 2 LAST SIG_NAME P5E_CPU1_P2_RX_BUF_DN<0>
J 0
(1665 -740);
DISPLAY 0.638298 (1665 -740);
WIRE 16 -1 (2800 -1250)(1550 -1250);
FORCEPROP 2 LAST SIG_NAME P5E_CPU1_P3_TX_BUF_C_DP<0>
J 0
(1665 -1240);
DISPLAY 0.638298 (1665 -1240);
WIRE 16 -1 (2800 850)(1550 850);
FORCEPROP 2 LAST SIG_NAME P5E_CPU1_P2_RX_BUF_DN<2>
J 0
(1665 860);
DISPLAY 0.638298 (1665 860);
WIRE 16 -1 (2800 1700)(1550 1700);
FORCEPROP 2 LAST SIG_NAME P5E_CPU1_P2_RX_BUF_DN<3>
J 0
(1665 1710);
DISPLAY 0.638298 (1665 1710);
WIRE 16 -1 (2800 1650)(1550 1650);
FORCEPROP 2 LAST SIG_NAME P5E_CPU1_P2_RX_BUF_DP<3>
J 0
(1665 1660);
DISPLAY 0.638298 (1665 1660);
WIRE 16 -1 (-1975 1650)(-3200 1650);
FORCEPROP 2 LAST SIG_NAME P5E_CPU1_P2_RX_BUF_DN<7>
J 0
(-3085 1660);
DISPLAY 0.638298 (-3085 1660);
WIRE 16 -1 (2800 800)(1550 800);
FORCEPROP 2 LAST SIG_NAME P5E_CPU1_P2_RX_BUF_DP<2>
J 0
(1665 810);
DISPLAY 0.638298 (1665 810);
WIRE 16 -1 (-1975 1600)(-3200 1600);
FORCEPROP 2 LAST SIG_NAME P5E_CPU1_P2_RX_BUF_DP<7>
J 0
(-3085 1610);
DISPLAY 0.638298 (-3085 1610);
DOT 1 (2575 -700);
DOT 1 (-2150 -1200);
DOT 1 (-2150 -1050);
DOT 1 (-2150 -900);
DOT 1 (-2150 850);
DOT 1 (-2150 -750);
DOT 1 (-2150 -1350);
DOT 1 (-2150 -200);
DOT 1 (-2150 -350);
DOT 1 (-2150 -50);
DOT 1 (-2150 100);
DOT 1 (-2150 250);
DOT 1 (-2150 550);
DOT 1 (-2150 400);
DOT 1 (-2150 700);
DOT 1 (-2150 1250);
DOT 1 (-2150 1100);
DOT 1 (-2150 1400);
DOT 1 (-2150 1550);
DOT 1 (2575 -1300);
DOT 1 (2575 -1150);
DOT 1 (2575 -1000);
DOT 1 (2575 -850);
DOT 1 (2575 -450);
DOT 1 (2575 -300);
DOT 1 (2575 0);
DOT 1 (2575 -150);
DOT 1 (2575 150);
DOT 1 (2575 300);
DOT 1 (2575 450);
DOT 1 (2575 600);
DOT 1 (2575 750);
DOT 1 (2575 900);
DOT 1 (2575 1300);
DOT 1 (2575 1150);
DOT 1 (2575 1450);
DOT 1 (2575 1600);
DOT 1 (-2150 -500);
FORCENOTE
CPU1_P2_TX/RX<0-15> LANE REVERSAL
(-4525 2275) 0;
DISPLAY LEFT (-4525 2275);
DISPLAY 1.595745 (-4525 2275);
PAINT PINK (-4525 2275);
FORCENOTE
CPU1_P3_TX/RX<0-15> LANE REVERSAL
(-4525 2175) 0;
DISPLAY LEFT (-4525 2175);
DISPLAY 1.595745 (-4525 2175);
PAINT PINK (-4525 2175);
QUIT
